G04 ================== begin FILE IDENTIFICATION RECORD ==================*
G04 Layout Name:  9054_F0T_PDB_BD_GPU_F_V04_1213_1550.brd*
G04 Film Name:    gnd*
G04 File Format:  Gerber RS274X*
G04 File Origin:  Cadence Allegro 17.2-S081*
G04 Origin Date:  Wed Dec 28 10:19:02 2022*
G04 *
G04 Layer:  DRAWING FORMAT/TITLE_BLOCK_A*
G04 Layer:  PIN/SPECIAL_DRILL*
G04 Layer:  DRAWING FORMAT/TITLE_BLOCK*
G04 Layer:  VIA CLASS/GND*
G04 Layer:  PIN/GND*
G04 Layer:  MANUFACTURING/PHOTOPLOT_OUTLINE*
G04 Layer:  ETCH/GND*
G04 Layer:  DRAWING FORMAT/TITLE_DATA_GND*
G04 *
G04 Offset:    (0.00 0.00)*
G04 Mirror:    No*
G04 Mode:      Negative*
G04 Rotation:  0*
G04 FullContactRelief:  No*
G04 UndefLineWidth:     6.00*
G04 ================== end FILE IDENTIFICATION RECORD ====================*
%FSLAX25Y25*MOIN*%
%IR0*IPPOS*OFA0.00000B0.00000*MIA0B0*SFA1.00000B1.00000*%
%ADD17C,.03*%
%ADD47C,.061*%
%ADD20C,.07*%
%ADD42C,.026*%
%ADD19C,.07*%
%AMMACRO15*
4,1,36,0.0,.01,
-.001736,.009848,
-.00342,.009397,
-.005,.00866,
-.006428,.00766,
-.00766,.006428,
-.00866,.005,
-.009397,.00342,
-.009848,.001736,
-.01,0.0,
-.009848,-.001736,
-.009397,-.00342,
-.00866,-.005,
-.00766,-.006428,
-.006428,-.00766,
-.005,-.00866,
-.00342,-.009397,
-.001736,-.009848,
0.0,-.01,
.001736,-.009848,
.00342,-.009397,
.005,-.00866,
.006428,-.00766,
.00766,-.006428,
.00866,-.005,
.009397,-.00342,
.009848,-.001736,
.01,0.0,
.009848,.001736,
.009397,.00342,
.00866,.005,
.00766,.006428,
.006428,.00766,
.005,.00866,
.00342,.009397,
.001736,.009848,
0.0,.01,
0.0*
%
%ADD15MACRO15*%
%AMMACRO29*
4,1,36,.0025,0.0,
.002462,.000434,
.002349,.000855,
.002165,.00125,
.001915,.001607,
.001607,.001915,
.00125,.002165,
.000855,.002349,
.000434,.002462,
0.0,.0025,
-.000434,.002462,
-.000855,.002349,
-.00125,.002165,
-.001607,.001915,
-.001915,.001607,
-.002165,.00125,
-.002349,.000855,
-.002462,.000434,
-.0025,0.0,
-.002462,-.000434,
-.002349,-.000855,
-.002165,-.00125,
-.001915,-.001607,
-.001607,-.001915,
-.00125,-.002165,
-.000855,-.002349,
-.000434,-.002462,
0.0,-.0025,
.000434,-.002462,
.000855,-.002349,
.00125,-.002165,
.001607,-.001915,
.001915,-.001607,
.002165,-.00125,
.002349,-.000855,
.002462,-.000434,
.0025,0.0,
270.*
%
%ADD29MACRO29*%
%AMMACRO28*
4,1,36,.0025,0.0,
.002462,.000434,
.002349,.000855,
.002165,.00125,
.001915,.001607,
.001607,.001915,
.00125,.002165,
.000855,.002349,
.000434,.002462,
0.0,.0025,
-.000434,.002462,
-.000855,.002349,
-.00125,.002165,
-.001607,.001915,
-.001915,.001607,
-.002165,.00125,
-.002349,.000855,
-.002462,.000434,
-.0025,0.0,
-.002462,-.000434,
-.002349,-.000855,
-.002165,-.00125,
-.001915,-.001607,
-.001607,-.001915,
-.00125,-.002165,
-.000855,-.002349,
-.000434,-.002462,
0.0,-.0025,
.000434,-.002462,
.000855,-.002349,
.00125,-.002165,
.001607,-.001915,
.001915,-.001607,
.002165,-.00125,
.002349,-.000855,
.002462,-.000434,
.0025,0.0,
180.*
%
%ADD28MACRO28*%
%ADD37C,.066*%
%ADD34C,.06015*%
%ADD31C,.087*%
%AMMACRO21*
4,1,36,0.0,.0135,
-.002344,.013295,
-.004617,.012686,
-.00675,.011691,
-.008678,.010342,
-.010342,.008678,
-.011691,.00675,
-.012686,.004617,
-.013295,.002344,
-.0135,0.0,
-.013295,-.002344,
-.012686,-.004617,
-.011691,-.00675,
-.010342,-.008678,
-.008678,-.010342,
-.00675,-.011691,
-.004617,-.012686,
-.002344,-.013295,
0.0,-.0135,
.002344,-.013295,
.004617,-.012686,
.00675,-.011691,
.008678,-.010342,
.010342,-.008678,
.011691,-.00675,
.012686,-.004617,
.013295,-.002344,
.0135,0.0,
.013295,.002344,
.012686,.004617,
.011691,.00675,
.010342,.008678,
.008678,.010342,
.00675,.011691,
.004617,.012686,
.002344,.013295,
0.0,.0135,
0.0*
%
%ADD21MACRO21*%
%AMMACRO43*
4,1,17,.09027,.06198,
.099661,.045363,
.106024,.027368,
.109166,.008541,
.108991,-.010545,
.105504,-.029311,
.098811,-.047186,
.09027,-.06198,
.0953,-.06701,
.105488,-.049443,
.112471,-.030374,
.116037,-.010382,
.116077,.009925,
.11259,.029931,
.105682,.049027,
.095563,.066634,
.0953,.06701,
.09027,.06198,
90.*
4,1,17,.06198,-.09027,
.045363,-.099661,
.027368,-.106024,
.008541,-.109166,
-.010545,-.108991,
-.029311,-.105504,
-.047186,-.098811,
-.06198,-.09027,
-.06701,-.0953,
-.049443,-.105488,
-.030374,-.112471,
-.010382,-.116037,
.009925,-.116077,
.029931,-.11259,
.049027,-.105682,
.066634,-.095563,
.06701,-.0953,
.06198,-.09027,
90.*
4,1,17,-.09027,-.06198,
-.099661,-.045363,
-.106024,-.027368,
-.109166,-.008541,
-.108991,.010545,
-.105504,.029311,
-.098811,.047186,
-.09027,.06198,
-.0953,.06701,
-.105488,.049443,
-.112471,.030374,
-.116037,.010382,
-.116077,-.009925,
-.11259,-.029931,
-.105682,-.049027,
-.095563,-.066634,
-.0953,-.06701,
-.09027,-.06198,
90.*
4,1,17,-.06198,.09027,
-.045363,.099661,
-.027368,.106024,
-.008541,.109166,
.010545,.108991,
.029311,.105504,
.047186,.098811,
.06198,.09027,
.06701,.0953,
.049443,.105488,
.030374,.112471,
.010382,.116037,
-.009925,.116077,
-.029931,.11259,
-.049027,.105682,
-.066634,.095563,
-.06701,.0953,
-.06198,.09027,
90.*
%
%ADD43MACRO43*%
%ADD18C,.04952*%
%AMMACRO45*
4,1,15,.02475,.01414,
.026829,.009627,
.028094,.004822,
.028504,-.000129,
.028049,-.005077,
.026741,-.009871,
.02475,-.01414,
.02984,-.01923,
.032726,-.013756,
.034617,-.007864,
.035457,-.001734,
.03522,.00445,
.033912,.010498,
.031574,.016227,
.02984,.01923,
.02475,.01414,
90.*
4,1,15,.01414,-.02475,
.009627,-.026829,
.004822,-.028094,
-.000129,-.028504,
-.005077,-.028049,
-.009871,-.026741,
-.01414,-.02475,
-.01923,-.02984,
-.013756,-.032726,
-.007864,-.034617,
-.001734,-.035457,
.00445,-.03522,
.010498,-.033912,
.016227,-.031574,
.01923,-.02984,
.01414,-.02475,
90.*
4,1,15,-.02475,-.01414,
-.026829,-.009627,
-.028094,-.004822,
-.028504,.000129,
-.028049,.005077,
-.026741,.009871,
-.02475,.01414,
-.02984,.01923,
-.032726,.013756,
-.034617,.007864,
-.035457,.001734,
-.03522,-.00445,
-.033912,-.010498,
-.031574,-.016227,
-.02984,-.01923,
-.02475,-.01414,
90.*
4,1,15,-.01414,.02475,
-.009627,.026829,
-.004822,.028094,
.000129,.028504,
.005077,.028049,
.009871,.026741,
.01414,.02475,
.01923,.02984,
.013756,.032726,
.007864,.034617,
.001734,.035457,
-.00445,.03522,
-.010498,.033912,
-.016227,.031574,
-.01923,.02984,
-.01414,.02475,
90.*
%
%ADD45MACRO45*%
%AMMACRO38*
4,1,16,.02657,.01597,
.02894,.011114,
.03043,.005919,
.030995,.000545,
.030619,-.004845,
.029313,-.010088,
.027115,-.015025,
.02657,-.01597,
.03164,-.02104,
.034813,-.015226,
.036928,-.00895,
.037921,-.002401,
.037762,.00422,
.036455,.010713,
.034041,.016881,
.03164,.02104,
.02657,.01597,
90.*
4,1,16,.01597,-.02657,
.011114,-.02894,
.005919,-.03043,
.000545,-.030995,
-.004845,-.030619,
-.010088,-.029313,
-.015025,-.027115,
-.01597,-.02657,
-.02104,-.03164,
-.015226,-.034813,
-.00895,-.036928,
-.002401,-.037921,
.00422,-.037762,
.010713,-.036455,
.016881,-.034041,
.02104,-.03164,
.01597,-.02657,
90.*
4,1,16,-.02657,-.01597,
-.02894,-.011114,
-.03043,-.005919,
-.030995,-.000545,
-.030619,.004845,
-.029313,.010088,
-.027115,.015025,
-.02657,.01597,
-.03164,.02104,
-.034813,.015226,
-.036928,.00895,
-.037921,.002401,
-.037762,-.00422,
-.036455,-.010713,
-.034041,-.016881,
-.03164,-.02104,
-.02657,-.01597,
90.*
4,1,16,-.01597,.02657,
-.011114,.02894,
-.005919,.03043,
-.000545,.030995,
.004845,.030619,
.010088,.029313,
.015025,.027115,
.01597,.02657,
.02104,.03164,
.015226,.034813,
.00895,.036928,
.002401,.037921,
-.00422,.037762,
-.010713,.036455,
-.016881,.034041,
-.02104,.03164,
-.01597,.02657,
90.*
%
%ADD38MACRO38*%
%AMMACRO41*
4,1,15,.03682,.01914,
.039584,.012455,
.041146,.005393,
.041457,-.001834,
.040509,-.009005,
.03833,-.015903,
.03682,-.01914,
.04197,-.0243,
.045552,-.016643,
.04775,-.00848,
.048497,-.000059,
.047771,.008363,
.045593,.016531,
.042029,.024197,
.04197,.0243,
.03682,.01914,
90.*
4,1,15,.01914,-.03682,
.012455,-.039584,
.005393,-.041146,
-.001834,-.041457,
-.009005,-.040509,
-.015903,-.03833,
-.01914,-.03682,
-.0243,-.04197,
-.016643,-.045552,
-.00848,-.04775,
-.000059,-.048497,
.008363,-.047771,
.016531,-.045593,
.024197,-.042029,
.0243,-.04197,
.01914,-.03682,
90.*
4,1,15,-.03682,-.01914,
-.039584,-.012455,
-.041146,-.005393,
-.041457,.001834,
-.040509,.009005,
-.03833,.015903,
-.03682,.01914,
-.04197,.0243,
-.045552,.016643,
-.04775,.00848,
-.048497,.000059,
-.047771,-.008363,
-.045593,-.016531,
-.042029,-.024197,
-.04197,-.0243,
-.03682,-.01914,
90.*
4,1,15,-.01914,.03682,
-.012455,.039584,
-.005393,.041146,
.001834,.041457,
.009005,.040509,
.015903,.03833,
.01914,.03682,
.0243,.04197,
.016643,.045552,
.00848,.04775,
.000059,.048497,
-.008363,.047771,
-.016531,.045593,
-.024197,.042029,
-.0243,.04197,
-.01914,.03682,
90.*
%
%ADD41MACRO41*%
%AMMACRO40*
4,1,15,-.03682,.01914,
-.039584,.012455,
-.041146,.005393,
-.041457,-.001834,
-.040509,-.009005,
-.03833,-.015903,
-.03682,-.01914,
-.04197,-.0243,
-.045552,-.016643,
-.04775,-.00848,
-.048497,-.000059,
-.047771,.008363,
-.045593,.016531,
-.042029,.024197,
-.04197,.0243,
-.03682,.01914,
90.*
4,1,15,-.01914,-.03682,
-.012455,-.039584,
-.005393,-.041146,
.001834,-.041457,
.009005,-.040509,
.015903,-.03833,
.01914,-.03682,
.0243,-.04197,
.016643,-.045552,
.00848,-.04775,
.000059,-.048497,
-.008363,-.047771,
-.016531,-.045593,
-.024197,-.042029,
-.0243,-.04197,
-.01914,-.03682,
90.*
4,1,15,.03682,-.01914,
.039584,-.012455,
.041146,-.005393,
.041457,.001834,
.040509,.009005,
.03833,.015903,
.03682,.01914,
.04197,.0243,
.045552,.016643,
.04775,.00848,
.048497,.000059,
.047771,-.008363,
.045593,-.016531,
.042029,-.024197,
.04197,-.0243,
.03682,-.01914,
90.*
4,1,15,.01914,.03682,
.012455,.039584,
.005393,.041146,
-.001834,.041457,
-.009005,.040509,
-.015903,.03833,
-.01914,.03682,
-.0243,.04197,
-.016643,.045552,
-.00848,.04775,
-.000059,.048497,
.008363,.047771,
.016531,.045593,
.024197,.042029,
.0243,.04197,
.01914,.03682,
90.*
%
%ADD40MACRO40*%
%ADD25C,.113*%
%AMMACRO14*
4,1,36,0.0,.005,
.000868,.004924,
.00171,.004698,
.0025,.00433,
.003214,.00383,
.00383,.003214,
.00433,.0025,
.004698,.00171,
.004924,.000868,
.005,0.0,
.004924,-.000868,
.004698,-.00171,
.00433,-.0025,
.00383,-.003214,
.003214,-.00383,
.0025,-.00433,
.00171,-.004698,
.000868,-.004924,
0.0,-.005,
-.000868,-.004924,
-.00171,-.004698,
-.0025,-.00433,
-.003214,-.00383,
-.00383,-.003214,
-.00433,-.0025,
-.004698,-.00171,
-.004924,-.000868,
-.005,0.0,
-.004924,.000868,
-.004698,.00171,
-.00433,.0025,
-.00383,.003214,
-.003214,.00383,
-.0025,.00433,
-.00171,.004698,
-.000868,.004924,
0.0,.005,
180.*
%
%ADD14MACRO14*%
%ADD27C,.115*%
%ADD46C,.116*%
%ADD10C,.125*%
%ADD23C,.155*%
%ADD35C,.256*%
%AMMACRO26*
4,1,36,0.0,.0135,
-.002344,.013295,
-.004617,.012686,
-.00675,.011691,
-.008678,.010342,
-.010342,.008678,
-.011691,.00675,
-.012686,.004617,
-.013295,.002344,
-.0135,0.0,
-.013295,-.002344,
-.012686,-.004617,
-.011691,-.00675,
-.010342,-.008678,
-.008678,-.010342,
-.00675,-.011691,
-.004617,-.012686,
-.002344,-.013295,
0.0,-.0135,
.002344,-.013295,
.004617,-.012686,
.00675,-.011691,
.008678,-.010342,
.010342,-.008678,
.011691,-.00675,
.012686,-.004617,
.013295,-.002344,
.0135,0.0,
.013295,.002344,
.012686,.004617,
.011691,.00675,
.010342,.008678,
.008678,.010342,
.00675,.011691,
.004617,.012686,
.002344,.013295,
0.0,.0135,
270.*
%
%ADD26MACRO26*%
%AMMACRO22*
4,1,36,0.0,.0135,
-.002344,.013295,
-.004617,.012686,
-.00675,.011691,
-.008678,.010342,
-.010342,.008678,
-.011691,.00675,
-.012686,.004617,
-.013295,.002344,
-.0135,0.0,
-.013295,-.002344,
-.012686,-.004617,
-.011691,-.00675,
-.010342,-.008678,
-.008678,-.010342,
-.00675,-.011691,
-.004617,-.012686,
-.002344,-.013295,
0.0,-.0135,
.002344,-.013295,
.004617,-.012686,
.00675,-.011691,
.008678,-.010342,
.010342,-.008678,
.011691,-.00675,
.012686,-.004617,
.013295,-.002344,
.0135,0.0,
.013295,.002344,
.012686,.004617,
.011691,.00675,
.010342,.008678,
.008678,.010342,
.00675,.011691,
.004617,.012686,
.002344,.013295,
0.0,.0135,
180.*
%
%ADD22MACRO22*%
%AMMACRO24*
4,1,36,.0025,0.0,
.002462,.000434,
.002349,.000855,
.002165,.00125,
.001915,.001607,
.001607,.001915,
.00125,.002165,
.000855,.002349,
.000434,.002462,
0.0,.0025,
-.000434,.002462,
-.000855,.002349,
-.00125,.002165,
-.001607,.001915,
-.001915,.001607,
-.002165,.00125,
-.002349,.000855,
-.002462,.000434,
-.0025,0.0,
-.002462,-.000434,
-.002349,-.000855,
-.002165,-.00125,
-.001915,-.001607,
-.001607,-.001915,
-.00125,-.002165,
-.000855,-.002349,
-.000434,-.002462,
0.0,-.0025,
.000434,-.002462,
.000855,-.002349,
.00125,-.002165,
.001607,-.001915,
.001915,-.001607,
.002165,-.00125,
.002349,-.000855,
.002462,-.000434,
.0025,0.0,
90.*
%
%ADD24MACRO24*%
%ADD36C,.187*%
%AMMACRO33*
4,1,36,0.0,.019,
-.003299,.018711,
-.006498,.017854,
-.0095,.016454,
-.012213,.014555,
-.014555,.012213,
-.016454,.0095,
-.017854,.006498,
-.018711,.003299,
-.019,0.0,
-.018711,-.003299,
-.017854,-.006498,
-.016454,-.0095,
-.014555,-.012213,
-.012213,-.014555,
-.0095,-.016454,
-.006498,-.017854,
-.003299,-.018711,
0.0,-.019,
.003299,-.018711,
.006498,-.017854,
.0095,-.016454,
.012213,-.014555,
.014555,-.012213,
.016454,-.0095,
.017854,-.006498,
.018711,-.003299,
.019,0.0,
.018711,.003299,
.017854,.006498,
.016454,.0095,
.014555,.012213,
.012213,.014555,
.0095,.016454,
.006498,.017854,
.003299,.018711,
0.0,.019,
180.*
%
%ADD33MACRO33*%
%AMMACRO11*
4,1,36,.0025,0.0,
.002462,.000434,
.002349,.000855,
.002165,.00125,
.001915,.001607,
.001607,.001915,
.00125,.002165,
.000855,.002349,
.000434,.002462,
0.0,.0025,
-.000434,.002462,
-.000855,.002349,
-.00125,.002165,
-.001607,.001915,
-.001915,.001607,
-.002165,.00125,
-.002349,.000855,
-.002462,.000434,
-.0025,0.0,
-.002462,-.000434,
-.002349,-.000855,
-.002165,-.00125,
-.001915,-.001607,
-.001607,-.001915,
-.00125,-.002165,
-.000855,-.002349,
-.000434,-.002462,
0.0,-.0025,
.000434,-.002462,
.000855,-.002349,
.00125,-.002165,
.001607,-.001915,
.001915,-.001607,
.002165,-.00125,
.002349,-.000855,
.002462,-.000434,
.0025,0.0,
0.0*
%
%ADD11MACRO11*%
%ADD16C,.188*%
%AMMACRO44*
4,1,21,-.0075,-.06379,
-.0075,-.0709,
-.015443,-.068892,
-.022917,-.065536,
-.029695,-.060932,
-.03557,-.055222,
-.040364,-.048578,
-.043932,-.041203,
-.046165,-.03332,
-.046995,-.025169,
-.047,-.0245,
-.047,-.0075,
-.04,-.0075,
-.04,-.0245,
-.039392,-.031446,
-.037588,-.038181,
-.034641,-.0445,
-.030642,-.050211,
-.025712,-.055141,
-.02,-.05914,
-.013681,-.062087,
-.0075,-.06379,
90.*
4,1,21,.0075,-.0709,
.0075,-.06379,
.014209,-.061891,
.020486,-.058856,
.02614,-.054776,
.031001,-.049777,
.034919,-.04401,
.037776,-.03765,
.039486,-.030891,
.04,-.0245,
.04,-.0075,
.047,-.0075,
.047,-.0245,
.046286,-.032662,
.044165,-.040576,
.040703,-.048001,
.036003,-.054713,
.03021,-.060506,
.023499,-.065205,
.016073,-.068668,
.008159,-.070789,
.0075,-.0709,
90.*
4,1,21,-.0075,.0709,
-.0075,.06379,
-.014209,.061891,
-.020486,.058856,
-.02614,.054776,
-.031001,.049777,
-.034919,.04401,
-.037776,.03765,
-.039486,.030891,
-.04,.0245,
-.04,.0075,
-.047,.0075,
-.047,.0245,
-.046286,.032662,
-.044165,.040576,
-.040703,.048001,
-.036003,.054713,
-.03021,.060506,
-.023499,.065205,
-.016073,.068668,
-.008159,.070789,
-.0075,.0709,
90.*
4,1,21,.0075,.06379,
.0075,.0709,
.015443,.068892,
.022917,.065536,
.029695,.060932,
.03557,.055222,
.040364,.048578,
.043932,.041203,
.046165,.03332,
.046995,.025169,
.047,.0245,
.047,.0075,
.04,.0075,
.04,.0245,
.039392,.031446,
.037588,.038181,
.034641,.0445,
.030642,.050211,
.025712,.055141,
.02,.05914,
.013681,.062087,
.0075,.06379,
90.*
%
%ADD44MACRO44*%
%AMMACRO39*
4,1,16,.02657,.01597,
.02894,.011114,
.03043,.005919,
.030995,.000545,
.030619,-.004845,
.029313,-.010088,
.027115,-.015025,
.02657,-.01597,
.03164,-.02104,
.034813,-.015226,
.036928,-.00895,
.037921,-.002401,
.037762,.00422,
.036455,.010713,
.034041,.016881,
.03164,.02104,
.02657,.01597,
270.*
4,1,16,.01597,-.02657,
.011114,-.02894,
.005919,-.03043,
.000545,-.030995,
-.004845,-.030619,
-.010088,-.029313,
-.015025,-.027115,
-.01597,-.02657,
-.02104,-.03164,
-.015226,-.034813,
-.00895,-.036928,
-.002401,-.037921,
.00422,-.037762,
.010713,-.036455,
.016881,-.034041,
.02104,-.03164,
.01597,-.02657,
270.*
4,1,16,-.02657,-.01597,
-.02894,-.011114,
-.03043,-.005919,
-.030995,-.000545,
-.030619,.004845,
-.029313,.010088,
-.027115,.015025,
-.02657,.01597,
-.03164,.02104,
-.034813,.015226,
-.036928,.00895,
-.037921,.002401,
-.037762,-.00422,
-.036455,-.010713,
-.034041,-.016881,
-.03164,-.02104,
-.02657,-.01597,
270.*
4,1,16,-.01597,.02657,
-.011114,.02894,
-.005919,.03043,
-.000545,.030995,
.004845,.030619,
.010088,.029313,
.015025,.027115,
.01597,.02657,
.02104,.03164,
.015226,.034813,
.00895,.036928,
.002401,.037921,
-.00422,.037762,
-.010713,.036455,
-.016881,.034041,
-.02104,.03164,
-.01597,.02657,
270.*
%
%ADD39MACRO39*%
%AMMACRO12*
4,1,18,.10783,.07955,
.120006,.059617,
.128535,.037873,
.133159,.014977,
.133736,-.008373,
.130251,-.031469,
.122807,-.053609,
.111633,-.074119,
.10783,-.07955,
.11284,-.08455,
.125808,-.063671,
.134953,-.040857,
.139997,-.016802,
.140788,.007763,
.137301,.032093,
.129642,.055447,
.118045,.077117,
.11284,.08455,
.10783,.07955,
180.*
4,1,18,.07955,-.10783,
.059617,-.120006,
.037873,-.128535,
.014977,-.133159,
-.008373,-.133736,
-.031469,-.130251,
-.053609,-.122807,
-.074119,-.111633,
-.07955,-.10783,
-.08455,-.11284,
-.063671,-.125808,
-.040857,-.134953,
-.016802,-.139997,
.007763,-.140788,
.032093,-.137301,
.055447,-.129642,
.077117,-.118045,
.08455,-.11284,
.07955,-.10783,
180.*
4,1,18,-.10783,-.07955,
-.120006,-.059617,
-.128535,-.037873,
-.133159,-.014977,
-.133736,.008373,
-.130251,.031469,
-.122807,.053609,
-.111633,.074119,
-.10783,.07955,
-.11284,.08455,
-.125808,.063671,
-.134953,.040857,
-.139997,.016802,
-.140788,-.007763,
-.137301,-.032093,
-.129642,-.055447,
-.118045,-.077117,
-.11284,-.08455,
-.10783,-.07955,
180.*
4,1,18,-.07955,.10783,
-.059617,.120006,
-.037873,.128535,
-.014977,.133159,
.008373,.133736,
.031469,.130251,
.053609,.122807,
.074119,.111633,
.07955,.10783,
.08455,.11284,
.063671,.125808,
.040857,.134953,
.016802,.139997,
-.007763,.140788,
-.032093,.137301,
-.055447,.129642,
-.077117,.118045,
-.08455,.11284,
-.07955,.10783,
180.*
%
%ADD12MACRO12*%
%AMMACRO30*
4,1,15,.03682,.01914,
.039584,.012455,
.041146,.005393,
.041457,-.001834,
.040509,-.009005,
.03833,-.015903,
.03682,-.01914,
.04197,-.0243,
.045552,-.016643,
.04775,-.00848,
.048497,-.000059,
.047771,.008363,
.045593,.016531,
.042029,.024197,
.04197,.0243,
.03682,.01914,
270.*
4,1,15,.01914,-.03682,
.012455,-.039584,
.005393,-.041146,
-.001834,-.041457,
-.009005,-.040509,
-.015903,-.03833,
-.01914,-.03682,
-.0243,-.04197,
-.016643,-.045552,
-.00848,-.04775,
-.000059,-.048497,
.008363,-.047771,
.016531,-.045593,
.024197,-.042029,
.0243,-.04197,
.01914,-.03682,
270.*
4,1,15,-.03682,-.01914,
-.039584,-.012455,
-.041146,-.005393,
-.041457,.001834,
-.040509,.009005,
-.03833,.015903,
-.03682,.01914,
-.04197,.0243,
-.045552,.016643,
-.04775,.00848,
-.048497,.000059,
-.047771,-.008363,
-.045593,-.016531,
-.042029,-.024197,
-.04197,-.0243,
-.03682,-.01914,
270.*
4,1,15,-.01914,.03682,
-.012455,.039584,
-.005393,.041146,
.001834,.041457,
.009005,.040509,
.015903,.03833,
.01914,.03682,
.0243,.04197,
.016643,.045552,
.00848,.04775,
.000059,.048497,
-.008363,.047771,
-.016531,.045593,
-.024197,.042029,
-.0243,.04197,
-.01914,.03682,
270.*
%
%ADD30MACRO30*%
%AMMACRO32*
4,1,15,-.03682,.01914,
-.039584,.012455,
-.041146,.005393,
-.041457,-.001834,
-.040509,-.009005,
-.03833,-.015903,
-.03682,-.01914,
-.04197,-.0243,
-.045552,-.016643,
-.04775,-.00848,
-.048497,-.000059,
-.047771,.008363,
-.045593,.016531,
-.042029,.024197,
-.04197,.0243,
-.03682,.01914,
270.*
4,1,15,-.01914,-.03682,
-.012455,-.039584,
-.005393,-.041146,
.001834,-.041457,
.009005,-.040509,
.015903,-.03833,
.01914,-.03682,
.0243,-.04197,
.016643,-.045552,
.00848,-.04775,
.000059,-.048497,
-.008363,-.047771,
-.016531,-.045593,
-.024197,-.042029,
-.0243,-.04197,
-.01914,-.03682,
270.*
4,1,15,.03682,-.01914,
.039584,-.012455,
.041146,-.005393,
.041457,.001834,
.040509,.009005,
.03833,.015903,
.03682,.01914,
.04197,.0243,
.045552,.016643,
.04775,.00848,
.048497,.000059,
.047771,-.008363,
.045593,-.016531,
.042029,-.024197,
.04197,-.0243,
.03682,-.01914,
270.*
4,1,15,.01914,.03682,
.012455,.039584,
.005393,.041146,
-.001834,.041457,
-.009005,.040509,
-.015903,.03833,
-.01914,.03682,
-.0243,.04197,
-.016643,.045552,
-.00848,.04775,
-.000059,.048497,
.008363,.047771,
.016531,.045593,
.024197,.042029,
.0243,.04197,
.01914,.03682,
270.*
%
%ADD32MACRO32*%
%ADD48C,.02*%
%ADD49C,.006*%
%ADD57C,.0801*%
%ADD56C,.07006*%
%ADD59C,.09558*%
%ADD60C,.11022*%
%ADD58C,.12006*%
%ADD55C,.11708*%
%ADD51C,.12608*%
%ADD54C,.13509*%
%ADD52C,.16506*%
%ADD50C,.28606*%
%ADD53C,.19806*%
G75*
%LPD*%
G75*
G36*
G01X-457143Y-1211429D02*
X4308572D01*
Y2242857D01*
X-457143D01*
Y-1211429D01*
G37*
%LPC*%
G75*
G36*
G01X1854331Y516776D02*
G02X1872012Y499095I-1J-17682D01*
G01Y85709D01*
G02X1854331Y68028I-17681J0D01*
G01X1751968D01*
G03X1730279Y46339I1J-21690D01*
G01Y19685D01*
G02X1712598Y2004I-17681J0D01*
G01X19685D01*
G02X2004Y19685I0J17681D01*
G01Y603543D01*
G02X19685Y621224I17681J0D01*
G01X102362D01*
G03X124051Y642913I0J21689D01*
G01Y656102D01*
G02X141732Y673783I17681J0D01*
G01X295276D01*
G02X312957Y656102I0J-17681D01*
G01Y634965D01*
G03X326698Y621224I14799J1058D01*
G01X328740D01*
G02X346421Y603543I0J-17681D01*
G01Y435039D01*
G03X377952Y403508I31532J1D01*
G01X1252385D01*
X1252389Y403512D01*
X1256109D01*
X1256113Y403508D01*
X1354331D01*
G03X1385862Y435039I0J31531D01*
G01Y603543D01*
G02X1403543Y621224I17681J0D01*
G01X1405512D01*
G03X1419327Y635039I0J13815D01*
G01Y656102D01*
G02X1437008Y673783I17681J0D01*
G01X1590551D01*
G02X1608232Y656102I0J-17681D01*
G01Y642913D01*
G03X1629921Y621224I21689J0D01*
G01X1712598D01*
G02X1730279Y603543I0J-17681D01*
G01Y538465D01*
G03X1751968Y516776I21690J0D01*
G01X1854331D01*
G37*
G36*
G01X1866142Y783851D02*
G02X1872016Y777977I0J-5874D01*
G01Y534528D01*
G02X1866142Y528654I-5874J0D01*
G01X1751968D01*
G02X1742157Y538465I1J9811D01*
G01Y603543D01*
G03X1712598Y633102I-29559J0D01*
G01X1640064D01*
G02X1630253Y642913I0J9811D01*
G01Y738607D01*
G03X1620379Y748481I-9874J0D01*
G01X1383858D01*
G03X1373984Y738607I0J-9874D01*
G01Y435039D01*
G02X1354331Y415386I-19653J0D01*
G01X1154764D01*
G02X1148890Y421260I0J5874D01*
G01Y479449D01*
G03X1135079Y493260I-13811J0D01*
G01X550827D01*
G03X537016Y479449I0J-13811D01*
G01Y421260D01*
G02X531142Y415386I-5874J0D01*
G01X377952D01*
G02X358299Y435039I0J19653D01*
G01Y738607D01*
G03X348425Y748481I-9874J0D01*
G01X111905D01*
G03X102031Y738607I0J-9874D01*
G01Y642913D01*
G02X92220Y633102I-9811J0D01*
G01X7874D01*
G02X2000Y638976I0J5874D01*
G01Y777977D01*
G02X7874Y783851I5874J0D01*
G01X1866142D01*
G37*
%LPD*%
G75*
G36*
G01X695332Y327292D02*
G02X696613Y327534I1279J-3260D01*
G02X697201Y327485I4J-3502D01*
G03X697254Y327483I34J197D01*
G02X697597Y327500I345J-3483D01*
G01X697600D01*
G02X699019Y327199I-1J-3500D01*
G03X699026Y327196I82J182D01*
G03X699174I74J186D01*
G03X699181Y327199I-75J185D01*
G02X700600Y327500I1420J-3199D01*
G02Y320500I0J-3500D01*
G02X699181Y320801I1J3500D01*
G03X699174Y320804I-82J-182D01*
G03X699026I-74J-186D01*
G03X699019Y320801I75J-185D01*
G02X697600Y320500I-1420J3199D01*
G02X697030Y320547I2J3500D01*
G03X696977Y320548I-30J-198D01*
G01X696975D01*
G02X696613Y320530I-355J3484D01*
G02X695332Y320772I-2J3502D01*
G03X695185I-73J-186D01*
G02X693904Y320530I-1279J3260D01*
G02X692857Y320690I-1J3502D01*
G03X692841Y320694I-56J-192D01*
G03X692732Y320688I-44J-195D01*
G02X691601Y320500I-1132J3312D01*
G01X691600D01*
G02X690181Y320801I1J3500D01*
G03X690174Y320804I-82J-182D01*
G03X690026I-74J-186D01*
G03X690019Y320801I75J-185D01*
G02X688600Y320500I-1420J3199D01*
G02Y327500I0J3500D01*
G02X690019Y327199I-1J-3500D01*
G03X690026Y327196I82J182D01*
G03X690174I74J186D01*
G03X690181Y327199I-75J185D01*
G02X691600Y327500I1420J-3199D01*
G02X692640Y327342I0J-3500D01*
G03X692764Y327344I59J191D01*
G02X693904Y327534I1138J-3312D01*
G02X695185Y327292I2J-3502D01*
G03X695332I73J186D01*
G37*
G36*
G01X1320919Y197645D02*
G02X1320348Y197598I-572J3455D01*
G01X1320346D01*
G02X1323848Y201100I0J3502D01*
G02X1323142Y198991I-3503J0D01*
G03X1323527Y198355I319J-241D01*
G02X1324098Y198402I572J-3455D01*
G01X1324100D01*
G02X1320598Y194900I0J-3502D01*
G02X1321304Y197009I3503J0D01*
G03X1320919Y197645I-319J241D01*
G37*
G36*
G01Y153245D02*
G02X1320348Y153198I-572J3455D01*
G01X1320346D01*
G02X1323848Y156700I0J3502D01*
G02X1323142Y154591I-3503J0D01*
G03X1323527Y153955I319J-241D01*
G02X1324098Y154002I572J-3455D01*
G01X1324100D01*
G02X1320598Y150500I0J-3502D01*
G02X1321304Y152609I3503J0D01*
G03X1320919Y153245I-319J241D01*
G37*
G36*
G01X1563628Y664685D02*
Y664687D01*
G02X1568406Y669464I4778J-1D01*
G02X1572039Y667789I-1J-4779D01*
G03X1572191Y667719I152J130D01*
G01X1572495D01*
G03X1572647Y667789I0J200D01*
G02X1576280Y669464I3634J-3104D01*
G02X1581058Y664685I-1J-4779D01*
G02X1579384Y661052I-4779J0D01*
G03X1579314Y660900I130J-152D01*
G01Y660596D01*
G03X1579384Y660444I200J0D01*
G02Y653178I-3105J-3633D01*
G03X1579314Y653026I130J-152D01*
G01Y652722D01*
G03X1579384Y652570I200J0D01*
G02Y645304I-3105J-3633D01*
G03X1579314Y645152I130J-152D01*
G01Y644848D01*
G03X1579384Y644696I200J0D01*
G02Y637430I-3105J-3633D01*
G03X1579314Y637278I130J-152D01*
G01Y636974D01*
G03X1579384Y636822I200J0D01*
G02Y629556I-3105J-3633D01*
G03X1579314Y629404I130J-152D01*
G01Y629100D01*
G03X1579384Y628948I200J0D01*
G02Y621682I-3105J-3633D01*
G03X1579314Y621530I130J-152D01*
G01Y621226D01*
G03X1579384Y621074I200J0D01*
G02Y613808I-3105J-3633D01*
G03X1579314Y613656I130J-152D01*
G01Y613352D01*
G03X1579384Y613200I200J0D01*
G02Y605934I-3105J-3633D01*
G03X1579314Y605782I130J-152D01*
G01Y605478D01*
G03X1579384Y605326I200J0D01*
G02X1581058Y601693I-3105J-3633D01*
G01Y601691D01*
G02X1576280Y596914I-4778J1D01*
G02X1572647Y598589I1J4779D01*
G03X1572495Y598659I-152J-130D01*
G01X1572191D01*
G03X1572039Y598589I0J-200D01*
G02X1568406Y596914I-3634J3104D01*
G02X1563628Y601693I1J4779D01*
G02X1565302Y605326I4779J0D01*
G03X1565372Y605478I-130J152D01*
G01Y605782D01*
G03X1565302Y605934I-200J0D01*
G02Y613200I3105J3633D01*
G03X1565372Y613352I-130J152D01*
G01Y613656D01*
G03X1565302Y613808I-200J0D01*
G02Y621074I3105J3633D01*
G03X1565372Y621226I-130J152D01*
G01Y621530D01*
G03X1565302Y621682I-200J0D01*
G02Y628948I3105J3633D01*
G03X1565372Y629100I-130J152D01*
G01Y629404D01*
G03X1565302Y629556I-200J0D01*
G02Y636822I3105J3633D01*
G03X1565372Y636974I-130J152D01*
G01Y637278D01*
G03X1565302Y637430I-200J0D01*
G02Y644696I3105J3633D01*
G03X1565372Y644848I-130J152D01*
G01Y645152D01*
G03X1565302Y645304I-200J0D01*
G02Y652570I3105J3633D01*
G03X1565372Y652722I-130J152D01*
G01Y653026D01*
G03X1565302Y653178I-200J0D01*
G02Y660444I3105J3633D01*
G03X1565372Y660596I-130J152D01*
G01Y660900D01*
G03X1565302Y661052I-200J0D01*
G02X1563628Y664685I3105J3633D01*
G37*
G36*
G01X132524D02*
G02X137303Y669464I4779J0D01*
G02X140936Y667789I-1J-4779D01*
G03X141088Y667719I152J130D01*
G01X141392D01*
G03X141544Y667789I0J200D01*
G02X145177Y669464I3634J-3104D01*
G02X149956Y664685I0J-4779D01*
G02X148281Y661052I-4779J1D01*
G03X148211Y660900I130J-152D01*
G01Y660596D01*
G03X148281Y660444I200J0D01*
G02X149956Y656811I-3104J-3634D01*
G02X148281Y653178I-4779J1D01*
G03X148211Y653026I130J-152D01*
G01Y652722D01*
G03X148281Y652570I200J0D01*
G02X149956Y648937I-3104J-3634D01*
G02X148281Y645304I-4779J1D01*
G03X148211Y645152I130J-152D01*
G01Y644848D01*
G03X148281Y644696I200J0D01*
G02X149956Y641063I-3104J-3634D01*
G02X148281Y637430I-4779J1D01*
G03X148211Y637278I130J-152D01*
G01Y636974D01*
G03X148281Y636822I200J0D01*
G02X149956Y633189I-3104J-3634D01*
G02X148281Y629556I-4779J1D01*
G03X148211Y629404I130J-152D01*
G01Y629100D01*
G03X148281Y628948I200J0D01*
G02X149956Y625315I-3104J-3634D01*
G02X148281Y621682I-4779J1D01*
G03X148211Y621530I130J-152D01*
G01Y621226D01*
G03X148281Y621074I200J0D01*
G02X149956Y617441I-3104J-3634D01*
G02X148281Y613808I-4779J1D01*
G03X148211Y613656I130J-152D01*
G01Y613352D01*
G03X148281Y613200I200J0D01*
G02X149956Y609567I-3104J-3634D01*
G02X148281Y605934I-4779J1D01*
G03X148211Y605782I130J-152D01*
G01Y605478D01*
G03X148281Y605326I200J0D01*
G02X149956Y601693I-3104J-3634D01*
G02X145177Y596914I-4779J0D01*
G02X141544Y598589I1J4779D01*
G03X141392Y598659I-152J-130D01*
G01X141088D01*
G03X140936Y598589I0J-200D01*
G02X137303Y596914I-3634J3104D01*
G02X132524Y601693I0J4779D01*
G02X134199Y605326I4779J-1D01*
G03X134269Y605478I-130J152D01*
G01Y605782D01*
G03X134199Y605934I-200J0D01*
G02X132524Y609567I3104J3634D01*
G02X134199Y613200I4779J-1D01*
G03X134269Y613352I-130J152D01*
G01Y613656D01*
G03X134199Y613808I-200J0D01*
G02X132524Y617441I3104J3634D01*
G02X134199Y621074I4779J-1D01*
G03X134269Y621226I-130J152D01*
G01Y621530D01*
G03X134199Y621682I-200J0D01*
G02X132524Y625315I3104J3634D01*
G02X134199Y628948I4779J-1D01*
G03X134269Y629100I-130J152D01*
G01Y629404D01*
G03X134199Y629556I-200J0D01*
G02X132524Y633189I3104J3634D01*
G02X134199Y636822I4779J-1D01*
G03X134269Y636974I-130J152D01*
G01Y637278D01*
G03X134199Y637430I-200J0D01*
G02X132524Y641063I3104J3634D01*
G02X134199Y644696I4779J-1D01*
G03X134269Y644848I-130J152D01*
G01Y645152D01*
G03X134199Y645304I-200J0D01*
G02X132524Y648937I3104J3634D01*
G02X134199Y652570I4779J-1D01*
G03X134269Y652722I-130J152D01*
G01Y653026D01*
G03X134199Y653178I-200J0D01*
G02X132524Y656811I3104J3634D01*
G02X134199Y660444I4779J-1D01*
G03X134269Y660596I-130J152D01*
G01Y660900D01*
G03X134199Y661052I-200J0D01*
G02X132524Y664685I3104J3634D01*
G37*
G36*
G01X1530076Y638108D02*
X1530067Y638055D01*
X1530104Y637954D01*
X1530455Y637664D01*
X1530559Y637646D01*
X1530610Y637665D01*
G02X1532283Y637968I1675J-4476D01*
G02X1535916Y636293I-1J-4779D01*
G03X1536068Y636223I152J130D01*
G01X1536372D01*
G03X1536524Y636293I0J200D01*
G02X1540157Y637968I3634J-3104D01*
G02X1544936Y633189I0J-4779D01*
G02X1543261Y629556I-4779J1D01*
G03X1543191Y629404I130J-152D01*
G01Y629100D01*
G03X1543261Y628948I200J0D01*
G02X1544936Y625315I-3104J-3634D01*
G02X1543261Y621682I-4779J1D01*
G03X1543191Y621530I130J-152D01*
G01Y621226D01*
G03X1543261Y621074I200J0D01*
G02X1544936Y617441I-3104J-3634D01*
G02X1540157Y612662I-4779J0D01*
G02X1536524Y614337I1J4779D01*
G03X1536372Y614407I-152J-130D01*
G01X1536068D01*
G03X1535916Y614337I0J-200D01*
G02X1532283Y612662I-3634J3104D01*
G02X1527504Y617441I0J4779D01*
G02X1529179Y621074I4779J-1D01*
G03X1529249Y621226I-130J152D01*
G01Y621530D01*
G03X1529179Y621682I-200J0D01*
G02X1527504Y625315I3104J3634D01*
G02X1529179Y628948I4779J-1D01*
G03X1529249Y629100I-130J152D01*
G01Y629404D01*
G03X1529179Y629556I-200J0D01*
G02X1527504Y633189I3104J3634D01*
G02X1527518Y633540I4778J-15D01*
G01Y633542D01*
G03X1527431Y633722I-200J15D01*
G01X1527143Y633916D01*
G03X1526943Y633931I-113J-165D01*
G01X1526942Y633930D01*
G02X1521876I-2533J5164D01*
G01X1521875Y633931D01*
G03X1521675Y633916I-87J-180D01*
G01X1521387Y633722D01*
G03X1521300Y633542I113J-165D01*
G01Y633541D01*
G02X1521314Y633189I-4764J-366D01*
G02X1519639Y629556I-4779J1D01*
G03X1519569Y629404I130J-152D01*
G01Y629100D01*
G03X1519639Y628948I200J0D01*
G02X1521314Y625315I-3104J-3634D01*
G02X1519639Y621682I-4779J1D01*
G03X1519569Y621530I130J-152D01*
G01Y621226D01*
G03X1519639Y621074I200J0D01*
G02X1521314Y617441I-3104J-3634D01*
G02X1516535Y612662I-4779J0D01*
G02X1512902Y614337I1J4779D01*
G03X1512750Y614407I-152J-130D01*
G01X1512446D01*
G03X1512294Y614337I0J-200D01*
G02X1508661Y612662I-3634J3104D01*
G02X1503882Y617441I0J4779D01*
G02X1505557Y621074I4779J-1D01*
G03X1505627Y621226I-130J152D01*
G01Y621530D01*
G03X1505557Y621682I-200J0D01*
G02X1503882Y625315I3104J3634D01*
G02X1505557Y628948I4779J-1D01*
G03X1505627Y629100I-130J152D01*
G01Y629404D01*
G03X1505557Y629556I-200J0D01*
G02X1503882Y633189I3104J3634D01*
G02X1508661Y637968I4779J0D01*
G02X1512294Y636293I-1J-4779D01*
G03X1512446Y636223I152J130D01*
G01X1512750D01*
G03X1512902Y636293I0J200D01*
G02X1516535Y637968I3634J-3104D01*
G02X1518208Y637665I-2J-4779D01*
G01X1518259Y637646D01*
X1518363Y637664D01*
X1518714Y637954D01*
X1518751Y638055D01*
X1518742Y638108D01*
G02X1530076I5667J986D01*
G37*
G36*
G01X213541D02*
X213532Y638055D01*
X213569Y637954D01*
X213920Y637664D01*
X214024Y637646D01*
X214075Y637665D01*
G02X215748Y637968I1675J-4476D01*
G02X219381Y636293I-1J-4779D01*
G03X219533Y636223I152J130D01*
G01X219837D01*
G03X219989Y636293I0J200D01*
G02X223622Y637968I3634J-3104D01*
G02X228400Y633189I-1J-4779D01*
G02X226726Y629556I-4779J0D01*
G03X226656Y629404I130J-152D01*
G01Y629100D01*
G03X226726Y628948I200J0D01*
G02Y621682I-3105J-3633D01*
G03X226656Y621530I130J-152D01*
G01Y621226D01*
G03X226726Y621074I200J0D01*
G02X228400Y617441I-3105J-3633D01*
G01Y617439D01*
G02X223622Y612662I-4778J1D01*
G02X219989Y614337I1J4779D01*
G03X219837Y614407I-152J-130D01*
G01X219533D01*
G03X219381Y614337I0J-200D01*
G02X215748Y612662I-3634J3104D01*
G02X210970Y617441I1J4779D01*
G02X212644Y621074I4779J0D01*
G03X212714Y621226I-130J152D01*
G01Y621530D01*
G03X212644Y621682I-200J0D01*
G02Y628948I3105J3633D01*
G03X212714Y629100I-130J152D01*
G01Y629404D01*
G03X212644Y629556I-200J0D01*
G02X210970Y633189I3105J3633D01*
G02X210983Y633541I4778J0D01*
G01Y633542D01*
G03X210896Y633722I-200J15D01*
G01X210608Y633916D01*
G03X210408Y633931I-113J-165D01*
G01X210407Y633930D01*
G02X205341I-2533J5164D01*
G01X205340Y633931D01*
G03X205140Y633916I-87J-180D01*
G01X204852Y633722D01*
G03X204765Y633542I113J-165D01*
G01Y633541D01*
G02X204778Y633189I-4765J-352D01*
G02X203104Y629556I-4779J0D01*
G03X203034Y629404I130J-152D01*
G01Y629100D01*
G03X203104Y628948I200J0D01*
G02Y621682I-3105J-3633D01*
G03X203034Y621530I130J-152D01*
G01Y621226D01*
G03X203104Y621074I200J0D01*
G02X204778Y617441I-3105J-3633D01*
G01Y617439D01*
G02X200000Y612662I-4778J1D01*
G02X196367Y614337I1J4779D01*
G03X196215Y614407I-152J-130D01*
G01X195911D01*
G03X195759Y614337I0J-200D01*
G02X192126Y612662I-3634J3104D01*
G02X187348Y617441I1J4779D01*
G02X189022Y621074I4779J0D01*
G03X189092Y621226I-130J152D01*
G01Y621530D01*
G03X189022Y621682I-200J0D01*
G02Y628948I3105J3633D01*
G03X189092Y629100I-130J152D01*
G01Y629404D01*
G03X189022Y629556I-200J0D01*
G02X187348Y633189I3105J3633D01*
G01Y633191D01*
G02X192126Y637968I4778J-1D01*
G02X195759Y636293I-1J-4779D01*
G03X195911Y636223I152J130D01*
G01X196215D01*
G03X196367Y636293I0J200D01*
G02X200000Y637968I3634J-3104D01*
G02X201673Y637665I-2J-4779D01*
G01X201724Y637646D01*
X201828Y637664D01*
X202179Y637954D01*
X202216Y638055D01*
X202207Y638108D01*
G02X213541I5667J986D01*
G37*
G36*
G01X1476378Y637968D02*
G02X1480011Y636293I-1J-4779D01*
G03X1480163Y636223I152J130D01*
G01X1480467D01*
G03X1480619Y636293I0J200D01*
G02X1484252Y637968I3634J-3104D01*
G02X1489030Y633189I-1J-4779D01*
G02X1487356Y629556I-4779J0D01*
G03X1487286Y629404I130J-152D01*
G01Y629100D01*
G03X1487356Y628948I200J0D01*
G02Y621682I-3105J-3633D01*
G03X1487286Y621530I130J-152D01*
G01Y621226D01*
G03X1487356Y621074I200J0D01*
G02X1489030Y617441I-3105J-3633D01*
G01Y617439D01*
G02X1484252Y612662I-4778J1D01*
G02X1480619Y614337I1J4779D01*
G03X1480467Y614407I-152J-130D01*
G01X1480163D01*
G03X1480011Y614337I0J-200D01*
G02X1476378Y612662I-3634J3104D01*
G02X1471600Y617441I1J4779D01*
G02X1473274Y621074I4779J0D01*
G03X1473344Y621226I-130J152D01*
G01Y621530D01*
G03X1473274Y621682I-200J0D01*
G02X1472062Y623263I3103J3634D01*
G01X1472044Y623301D01*
X1471981Y623356D01*
X1471657Y623454D01*
G03X1471497Y623435I-58J-191D01*
G02X1465511I-2993J5030D01*
G03X1465351Y623454I-102J-172D01*
G01X1465027Y623356D01*
X1464964Y623301D01*
X1464946Y623263D01*
G02X1463734Y621682I-4315J2053D01*
G03X1463664Y621530I130J-152D01*
G01Y621226D01*
G03X1463734Y621074I200J0D01*
G02X1465408Y617441I-3105J-3633D01*
G01Y617439D01*
G02X1460630Y612662I-4778J1D01*
G02X1456997Y614337I1J4779D01*
G03X1456845Y614407I-152J-130D01*
G01X1456541D01*
G03X1456389Y614337I0J-200D01*
G02X1452756Y612662I-3634J3104D01*
G02X1447978Y617441I1J4779D01*
G02X1449652Y621074I4779J0D01*
G03X1449722Y621226I-130J152D01*
G01Y621530D01*
G03X1449652Y621682I-200J0D01*
G02Y628948I3105J3633D01*
G03X1449722Y629100I-130J152D01*
G01Y629404D01*
G03X1449652Y629556I-200J0D01*
G02X1447978Y633189I3105J3633D01*
G01Y633191D01*
G02X1452756Y637968I4778J-1D01*
G02X1456389Y636293I-1J-4779D01*
G03X1456541Y636223I152J130D01*
G01X1456845D01*
G03X1456997Y636293I0J200D01*
G02X1460630Y637968I3634J-3104D01*
G02X1465339Y634002I0J-4779D01*
G03X1465445Y633857I197J33D01*
G01X1465731Y633712D01*
G03X1465910Y633711I90J178D01*
G02X1471098I2594J-5246D01*
G01X1471141Y633690D01*
X1471234Y633691D01*
X1471563Y633857D01*
G03X1471669Y634002I-91J178D01*
G02X1476378Y637968I4709J-813D01*
G37*
G36*
G01X1424356Y633189D02*
Y633191D01*
G02X1429134Y637968I4778J-1D01*
G02X1432767Y636293I-1J-4779D01*
G03X1432919Y636223I152J130D01*
G01X1433223D01*
G03X1433375Y636293I0J200D01*
G02X1437008Y637968I3634J-3104D01*
G02X1441786Y633189I-1J-4779D01*
G02X1440112Y629556I-4779J0D01*
G03X1440042Y629404I130J-152D01*
G01Y629100D01*
G03X1440112Y628948I200J0D01*
G02Y621682I-3105J-3633D01*
G03X1440042Y621530I130J-152D01*
G01Y621226D01*
G03X1440112Y621074I200J0D01*
G02X1441786Y617441I-3105J-3633D01*
G01Y617439D01*
G02X1437008Y612662I-4778J1D01*
G02X1433375Y614337I1J4779D01*
G03X1433223Y614407I-152J-130D01*
G01X1432919D01*
G03X1432767Y614337I0J-200D01*
G02X1429134Y612662I-3634J3104D01*
G02X1424356Y617441I1J4779D01*
G02X1426030Y621074I4779J0D01*
G03X1426100Y621226I-130J152D01*
G01Y621530D01*
G03X1426030Y621682I-200J0D01*
G02Y628948I3105J3633D01*
G03X1426100Y629100I-130J152D01*
G01Y629404D01*
G03X1426030Y629556I-200J0D01*
G02X1424356Y633189I3105J3633D01*
G37*
G36*
G01X295276Y637968D02*
G02X298909Y636293I-1J-4779D01*
G03X299061Y636223I152J130D01*
G01X299365D01*
G03X299517Y636293I0J200D01*
G02X303150Y637968I3634J-3104D01*
G02X307928Y633189I-1J-4779D01*
G02X306254Y629556I-4779J0D01*
G03X306184Y629404I130J-152D01*
G01Y629100D01*
G03X306254Y628948I200J0D01*
G02Y621682I-3105J-3633D01*
G03X306184Y621530I130J-152D01*
G01Y621226D01*
G03X306254Y621074I200J0D01*
G02X307928Y617441I-3105J-3633D01*
G01Y617439D01*
G02X303150Y612662I-4778J1D01*
G02X299517Y614337I1J4779D01*
G03X299365Y614407I-152J-130D01*
G01X299061D01*
G03X298909Y614337I0J-200D01*
G02X295276Y612662I-3634J3104D01*
G02X290498Y617441I1J4779D01*
G02X292172Y621074I4779J0D01*
G03X292242Y621226I-130J152D01*
G01Y621530D01*
G03X292172Y621682I-200J0D01*
G02X290960Y623263I3103J3634D01*
G01X290942Y623301D01*
X290879Y623356D01*
X290555Y623454D01*
G03X290395Y623435I-58J-191D01*
G02X284409I-2993J5030D01*
G03X284249Y623454I-102J-172D01*
G01X283925Y623356D01*
X283862Y623301D01*
X283844Y623263D01*
G02X282632Y621682I-4315J2053D01*
G03X282562Y621530I130J-152D01*
G01Y621226D01*
G03X282632Y621074I200J0D01*
G02X284306Y617441I-3105J-3633D01*
G01Y617439D01*
G02X279528Y612662I-4778J1D01*
G02X275895Y614337I1J4779D01*
G03X275743Y614407I-152J-130D01*
G01X275439D01*
G03X275287Y614337I0J-200D01*
G02X271654Y612662I-3634J3104D01*
G02X266876Y617441I1J4779D01*
G02X268550Y621074I4779J0D01*
G03X268620Y621226I-130J152D01*
G01Y621530D01*
G03X268550Y621682I-200J0D01*
G02Y628948I3105J3633D01*
G03X268620Y629100I-130J152D01*
G01Y629404D01*
G03X268550Y629556I-200J0D01*
G02X266876Y633189I3105J3633D01*
G01Y633191D01*
G02X271654Y637968I4778J-1D01*
G02X275287Y636293I-1J-4779D01*
G03X275439Y636223I152J130D01*
G01X275743D01*
G03X275895Y636293I0J200D01*
G02X279528Y637968I3634J-3104D01*
G02X284237Y634002I0J-4779D01*
G03X284343Y633857I197J33D01*
G01X284629Y633712D01*
G03X284808Y633711I90J178D01*
G02X289996I2594J-5246D01*
G01X290039Y633690D01*
X290132Y633691D01*
X290461Y633857D01*
G03X290567Y634002I-91J178D01*
G02X295276Y637968I4709J-813D01*
G37*
G36*
G01X243254Y633189D02*
Y633191D01*
G02X248032Y637968I4778J-1D01*
G02X251665Y636293I-1J-4779D01*
G03X251817Y636223I152J130D01*
G01X252121D01*
G03X252273Y636293I0J200D01*
G02X255906Y637968I3634J-3104D01*
G02X260684Y633189I-1J-4779D01*
G02X259010Y629556I-4779J0D01*
G03X258940Y629404I130J-152D01*
G01Y629100D01*
G03X259010Y628948I200J0D01*
G02Y621682I-3105J-3633D01*
G03X258940Y621530I130J-152D01*
G01Y621226D01*
G03X259010Y621074I200J0D01*
G02X260684Y617441I-3105J-3633D01*
G01Y617439D01*
G02X255906Y612662I-4778J1D01*
G02X252273Y614337I1J4779D01*
G03X252121Y614407I-152J-130D01*
G01X251817D01*
G03X251665Y614337I0J-200D01*
G02X248032Y612662I-3634J3104D01*
G02X243254Y617441I1J4779D01*
G02X244928Y621074I4779J0D01*
G03X244998Y621226I-130J152D01*
G01Y621530D01*
G03X244928Y621682I-200J0D01*
G02Y628948I3105J3633D01*
G03X244998Y629100I-130J152D01*
G01Y629404D01*
G03X244928Y629556I-200J0D01*
G02X243254Y633189I3105J3633D01*
G37*
G36*
G01X1084241Y342083D02*
X1084359D01*
G03X1084490Y342133I-1J200D01*
G02X1086800Y343002I2309J-2634D01*
G01X1086803D01*
G02X1087983Y342797I-1J-3502D01*
G03X1088117I67J188D01*
G02X1089297Y343002I1181J-3297D01*
G01X1089300D01*
G02Y335998I0J-3502D01*
G01X1089297D01*
G02X1088117Y336203I1J3502D01*
G03X1087983I-67J-188D01*
G02X1086803Y335998I-1181J3297D01*
G01X1086800D01*
G02X1084490Y336867I-1J3503D01*
G03X1084359Y336917I-132J-150D01*
G01X1084241D01*
G03X1084110Y336867I1J-200D01*
G02X1081800Y335998I-2309J2634D01*
G01X1081797D01*
G02X1080617Y336203I1J3502D01*
G03X1080483I-67J-188D01*
G02X1079303Y335998I-1181J3297D01*
G01X1079300D01*
G02X1076832Y337015I0J3503D01*
G01X1076831Y337016D01*
G03X1076691Y337073I-140J-143D01*
G01X1076409D01*
G03X1076269Y337016I0J-200D01*
G01X1076268Y337015D01*
G02X1073800Y335998I-2468J2486D01*
G01X1073797D01*
G02X1072617Y336203I1J3502D01*
G03X1072483I-67J-188D01*
G02X1071303Y335998I-1181J3297D01*
G01X1071300D01*
G02X1068832Y337015I0J3503D01*
G01X1068831Y337016D01*
G03X1068691Y337073I-140J-143D01*
G01X1068409D01*
G03X1068269Y337016I0J-200D01*
G01X1068268Y337015D01*
G02X1065800Y335998I-2468J2486D01*
G01X1065797D01*
G02X1064617Y336203I1J3502D01*
G03X1064483I-67J-188D01*
G02X1063303Y335998I-1181J3297D01*
G01X1063300D01*
G02Y343002I0J3502D01*
G01X1063303D01*
G02X1064483Y342797I-1J-3502D01*
G03X1064617I67J188D01*
G02X1065797Y343002I1181J-3297D01*
G01X1065800D01*
G02X1068268Y341985I0J-3503D01*
G01X1068269Y341984D01*
G03X1068409Y341927I140J143D01*
G01X1068691D01*
G03X1068831Y341984I0J200D01*
G01X1068832Y341985D01*
G02X1071300Y343002I2468J-2486D01*
G01X1071303D01*
G02X1072483Y342797I-1J-3502D01*
G03X1072617I67J188D01*
G02X1073797Y343002I1181J-3297D01*
G01X1073800D01*
G02X1076268Y341985I0J-3503D01*
G01X1076269Y341984D01*
G03X1076409Y341927I140J143D01*
G01X1076691D01*
G03X1076831Y341984I0J200D01*
G01X1076832Y341985D01*
G02X1079300Y343002I2468J-2486D01*
G01X1079303D01*
G02X1080483Y342797I-1J-3502D01*
G03X1080617I67J188D01*
G02X1081797Y343002I1181J-3297D01*
G01X1081800D01*
G02X1084110Y342133I1J-3503D01*
G03X1084241Y342083I132J150D01*
G37*
G36*
G01X1197534Y318912D02*
Y318914D01*
G02X1201037Y315410I3503J-1D01*
G01X1200968D01*
X1200964D01*
X1200920Y315411D01*
X1200838Y315374D01*
X1200608Y315101D01*
G03X1200565Y314934I153J-129D01*
G02X1200630Y314264I-3438J-672D01*
G01Y314262D01*
G02X1197127Y317766I-3503J1D01*
G01X1197196D01*
X1197200D01*
X1197244Y317765D01*
X1197326Y317802D01*
X1197556Y318075D01*
G03X1197599Y318242I-153J129D01*
G02X1197534Y318912I3438J672D01*
G37*
G36*
G01X1176200Y312998D02*
X1176198D01*
G02X1174781Y313298I1J3502D01*
G03X1174619I-81J-183D01*
G02X1173202Y312998I-1418J3202D01*
G01X1173200D01*
G02Y320002I0J3502D01*
G01X1173202D01*
G02X1174619Y319702I-1J-3502D01*
G03X1174781I81J183D01*
G02X1176198Y320002I1418J-3202D01*
G01X1176200D01*
G02Y312998I0J-3502D01*
G37*
G36*
G01X587182Y310800D02*
Y310802D01*
G02X587482Y312219I3502J-1D01*
G03Y312381I-183J81D01*
G02X587182Y313798I3202J1418D01*
G01Y313800D01*
G02X594186I3502J0D01*
G01Y313798D01*
G02X593886Y312381I-3502J1D01*
G03Y312219I183J-81D01*
G02X594186Y310802I-3202J-1418D01*
G01Y310800D01*
G02X587182I-3502J0D01*
G37*
G36*
G01X1304198Y309900D02*
G02X1304498Y311319I3502J1D01*
G03Y311481I-183J81D01*
G02X1304198Y312898I3202J1418D01*
G01Y312900D01*
G02X1307700Y316402I3502J0D01*
G01X1307702D01*
G02X1309119Y316102I-1J-3502D01*
G03X1309281I81J183D01*
G02X1310698Y316402I1418J-3202D01*
G01X1310700D01*
G02X1314149Y313511I0J-3503D01*
G03X1314311Y313349I197J35D01*
G02X1317149Y310511I-611J-3449D01*
G03X1317311Y310349I197J35D01*
G02X1320149Y307511I-611J-3449D01*
G03X1320311Y307349I197J35D01*
G02X1323202Y303900I-612J-3449D01*
G01Y303898D01*
G02X1322902Y302481I-3502J1D01*
G03Y302319I183J-81D01*
G02X1323202Y300902I-3202J-1418D01*
G01Y300900D01*
G02X1319700Y297398I-3502J0D01*
G01X1319698D01*
G02X1318281Y297698I1J3502D01*
G03X1318119I-81J-183D01*
G02X1316700Y297398I-1418J3202D01*
G02X1315281Y297698I-1J3502D01*
G03X1315119I-81J-183D01*
G02X1313700Y297398I-1418J3202D01*
G02X1312281Y297698I-1J3502D01*
G03X1312119I-81J-183D01*
G02X1310700Y297398I-1418J3202D01*
G02X1309281Y297698I-1J3502D01*
G03X1309119I-81J-183D01*
G02X1307702Y297398I-1418J3202D01*
G01X1307700D01*
G02X1304198Y300900I0J3502D01*
G01Y300902D01*
G02X1304498Y302319I3502J-1D01*
G03Y302481I-183J81D01*
G02X1304198Y303900I3202J1418D01*
G02X1304498Y305319I3502J1D01*
G03Y305481I-183J81D01*
G02X1304198Y306900I3202J1418D01*
G02X1304498Y308319I3502J1D01*
G03Y308481I-183J81D01*
G02X1304198Y309900I3202J1418D01*
G37*
G36*
G01X1106661Y304198D02*
X1106659D01*
G02X1105242Y304498I1J3502D01*
G03X1105080I-81J-183D01*
G02X1103663Y304198I-1418J3202D01*
G01X1103661D01*
G02Y311202I0J3502D01*
G01X1103663D01*
G02X1105080Y310902I-1J-3502D01*
G03X1105242I81J183D01*
G02X1106659Y311202I1418J-3202D01*
G01X1106661D01*
G02Y304198I0J-3502D01*
G37*
G36*
G01X565091Y299090D02*
G02Y306094I0J3502D01*
G01X565092D01*
G02X567440Y305190I0J-3502D01*
G01X567469Y305164D01*
X567540Y305137D01*
X567853Y305143D01*
G03X567989Y305201I-5J200D01*
G02X570442Y306204I2453J-2499D01*
G01X570443D01*
G02Y299200I0J-3502D01*
G01X570442D01*
G02X568094Y300104I0J3502D01*
G01X568065Y300130D01*
X567994Y300157D01*
X567681Y300151D01*
G03X567545Y300093I5J-200D01*
G02X565092Y299090I-2453J2499D01*
G01X565091D01*
G37*
G36*
G01X1840590Y300433D02*
Y300435D01*
G02X1846142Y305986I5552J-1D01*
G02X1851100Y302933I0J-5552D01*
G01X1851125Y302882D01*
X1851221Y302823D01*
X1851693D01*
X1851789Y302882D01*
X1851814Y302933D01*
G02X1856772Y305986I4958J-2499D01*
G02X1862324Y300433I-1J-5553D01*
G02X1859785Y295769I-5553J0D01*
G01X1859742Y295741D01*
X1859693Y295652D01*
Y295214D01*
X1859742Y295125D01*
X1859785Y295097D01*
G02Y285769I-3014J-4664D01*
G01X1859742Y285741D01*
X1859693Y285652D01*
Y285214D01*
X1859742Y285125D01*
X1859785Y285097D01*
G02Y275769I-3014J-4664D01*
G01X1859742Y275741D01*
X1859693Y275652D01*
Y275214D01*
X1859742Y275125D01*
X1859785Y275097D01*
G02X1862324Y270433I-3014J-4664D01*
G01Y270431D01*
G02X1856772Y264880I-5552J1D01*
G02X1851814Y267933I0J5552D01*
G01X1851789Y267984D01*
X1851693Y268043D01*
X1851221D01*
X1851125Y267984D01*
X1851100Y267933D01*
G02X1846142Y264880I-4958J2499D01*
G02X1840590Y270433I1J5553D01*
G02X1843129Y275097I5553J0D01*
G01X1843172Y275125D01*
X1843221Y275214D01*
Y275652D01*
X1843172Y275741D01*
X1843129Y275769D01*
G02Y285097I3014J4664D01*
G01X1843172Y285125D01*
X1843221Y285214D01*
Y285652D01*
X1843172Y285741D01*
X1843129Y285769D01*
G02Y295097I3014J4664D01*
G01X1843172Y295125D01*
X1843221Y295214D01*
Y295652D01*
X1843172Y295741D01*
X1843129Y295769D01*
G02X1840590Y300433I3014J4664D01*
G37*
G36*
G01X1199059Y290701D02*
X1198941D01*
G03X1198810Y290651I1J-200D01*
G02X1196500Y289782I-2309J2634D01*
G02Y296786I0J3502D01*
G02X1198810Y295917I1J-3503D01*
G03X1198941Y295867I132J150D01*
G01X1199059D01*
G03X1199190Y295917I-1J200D01*
G02X1201500Y296786I2309J-2634D01*
G02Y289782I0J-3502D01*
G02X1199190Y290651I-1J3503D01*
G03X1199059Y290701I-132J-150D01*
G37*
G36*
G01X568040Y289065D02*
Y289066D01*
G02X568410Y290633I3502J0D01*
G03X568398Y290832I-179J89D01*
G02X567822Y292757I2926J1924D01*
G02X574828I3503J0D01*
G02X574457Y291189I-3503J1D01*
G03X574469Y290990I179J-89D01*
G02X575044Y289068I-2928J-1923D01*
G01Y289065D01*
G02X568040I-3502J0D01*
G37*
G36*
G01X1055300Y287398D02*
X1055297D01*
G02X1053834Y287719I2J3502D01*
G03X1053666I-84J-182D01*
G02X1052203Y287398I-1465J3181D01*
G01X1052200D01*
G02Y294402I0J3502D01*
G01X1052203D01*
G02X1053666Y294081I-2J-3502D01*
G03X1053834I84J182D01*
G02X1055297Y294402I1465J-3181D01*
G01X1055300D01*
G02Y287398I0J-3502D01*
G37*
G36*
G01X448738Y293502D02*
G02X450157Y293202I1J-3502D01*
G03X450319I81J183D01*
G02X451738Y293502I1418J-3202D01*
G02X453157Y293202I1J-3502D01*
G03X453319I81J183D01*
G02X454736Y293502I1418J-3202D01*
G01X454738D01*
G02X458240Y290000I0J-3502D01*
G01Y289998D01*
G02X457940Y288581I-3502J1D01*
G03Y288419I183J-81D01*
G02X458240Y287000I-3202J-1418D01*
G02X457940Y285581I-3502J-1D01*
G03Y285419I183J-81D01*
G02X458240Y284000I-3202J-1418D01*
G02X457940Y282581I-3502J-1D01*
G03Y282419I183J-81D01*
G02X458240Y281000I-3202J-1418D01*
G02X457940Y279581I-3502J-1D01*
G03Y279419I183J-81D01*
G02X458240Y278002I-3202J-1418D01*
G01Y278000D01*
G02X454738Y274498I-3502J0D01*
G01X454736D01*
G02X453319Y274798I1J3502D01*
G03X453157I-81J-183D01*
G02X451738Y274498I-1418J3202D01*
G02X450319Y274798I-1J3502D01*
G03X450157I-81J-183D01*
G02X448738Y274498I-1418J3202D01*
G02X447319Y274798I-1J3502D01*
G03X447157I-81J-183D01*
G02X445738Y274498I-1418J3202D01*
G02X444319Y274798I-1J3502D01*
G03X444157I-81J-183D01*
G02X442740Y274498I-1418J3202D01*
G01X442738D01*
G02X439236Y278000I0J3502D01*
G01Y278002D01*
G02X439536Y279419I3502J-1D01*
G03Y279581I-183J81D01*
G02X439236Y281000I3202J1418D01*
G02X439536Y282419I3502J1D01*
G03Y282581I-183J81D01*
G02X439236Y284000I3202J1418D01*
G02X439536Y285419I3502J1D01*
G03Y285581I-183J81D01*
G02X439236Y287000I3202J1418D01*
G02X439536Y288419I3502J1D01*
G03Y288581I-183J81D01*
G02X439236Y289998I3202J1418D01*
G01Y290000D01*
G02X442738Y293502I3502J0D01*
G01X442740D01*
G02X444157Y293202I-1J-3502D01*
G03X444319I81J183D01*
G02X445738Y293502I1418J-3202D01*
G02X447157Y293202I1J-3502D01*
G03X447319I81J183D01*
G02X448738Y293502I1418J-3202D01*
G37*
G36*
G01X586796Y282890D02*
G02X593800I3502J0D01*
G02X592588Y280240I-3503J0D01*
G03X592519Y280089I131J-151D01*
G01Y279785D01*
G03X592588Y279634I200J0D01*
G02X593800Y276984I-2291J-2650D01*
G02X586796I-3502J0D01*
G02X588008Y279634I3503J0D01*
G03X588077Y279785I-131J151D01*
G01Y280089D01*
G03X588008Y280240I-200J0D01*
G02X586796Y282890I2291J2650D01*
G37*
G36*
G01X1032500Y278298D02*
X1032498D01*
G02X1031081Y278598I1J3502D01*
G03X1030919I-81J-183D01*
G02X1029502Y278298I-1418J3202D01*
G01X1029500D01*
G02Y285302I0J3502D01*
G01X1029502D01*
G02X1030919Y285002I-1J-3502D01*
G03X1031081I81J183D01*
G02X1032498Y285302I1418J-3202D01*
G01X1032500D01*
G02Y278298I0J-3502D01*
G37*
G36*
G01X1059300Y276098D02*
X1059298D01*
G02X1057550Y276566I1J3502D01*
G03X1057350I-100J-173D01*
G02X1055602Y276098I-1749J3034D01*
G01X1055600D01*
G02Y283102I0J3502D01*
G01X1055602D01*
G02X1057350Y282634I-1J-3502D01*
G03X1057550I100J173D01*
G02X1059298Y283102I1749J-3034D01*
G01X1059300D01*
G02Y276098I0J-3502D01*
G37*
G36*
G01X715982Y278980D02*
G02X722986I3502J0D01*
G02X720657Y275680I-3502J0D01*
G01X720615Y275665D01*
X720553Y275604D01*
X720430Y275276D01*
G03X720442Y275108I187J-71D01*
G02X720886Y273403I-3058J-1707D01*
G01Y273400D01*
G02X713882I-3502J0D01*
G02X716211Y276700I3502J0D01*
G01X716253Y276715D01*
X716315Y276776D01*
X716438Y277104D01*
G03X716426Y277272I-187J71D01*
G02X715982Y278977I3058J1707D01*
G01Y278980D01*
G37*
G36*
G01X1041398Y278600D02*
G02X1048402I3502J0D01*
G02X1046073Y275300I-3502J0D01*
G01X1046031Y275285D01*
X1045969Y275224D01*
X1045846Y274896D01*
G03X1045858Y274728I187J-71D01*
G02X1046302Y273023I-3058J-1707D01*
G01Y273020D01*
G02X1039298I-3502J0D01*
G02X1041627Y276320I3502J0D01*
G01X1041669Y276335D01*
X1041731Y276396D01*
X1041854Y276724D01*
G03X1041842Y276892I-187J71D01*
G02X1041398Y278597I3058J1707D01*
G01Y278600D01*
G37*
G36*
G01X706684Y268898D02*
X706682D01*
G02X704934Y269366I1J3502D01*
G03X704734I-100J-173D01*
G02X702986Y268898I-1749J3034D01*
G01X702984D01*
G02Y275902I0J3502D01*
G01X702986D01*
G02X704734Y275434I-1J-3502D01*
G03X704934I100J173D01*
G02X706682Y275902I1749J-3034D01*
G01X706684D01*
G02Y268898I0J-3502D01*
G37*
G36*
G01X730600Y266498D02*
X730598D01*
G02X729181Y266798I1J3502D01*
G03X729019I-81J-183D01*
G02X727602Y266498I-1418J3202D01*
G01X727600D01*
G02Y273502I0J3502D01*
G01X727602D01*
G02X729019Y273202I-1J-3502D01*
G03X729181I81J183D01*
G02X730598Y273502I1418J-3202D01*
G01X730600D01*
G02Y266498I0J-3502D01*
G37*
G36*
G01X1313700Y272002D02*
G02X1315119Y271702I1J-3502D01*
G03X1315281I81J183D01*
G02X1316700Y272002I1418J-3202D01*
G02X1318119Y271702I1J-3502D01*
G03X1318281I81J183D01*
G02X1319698Y272002I1418J-3202D01*
G01X1319700D01*
G02X1323202Y268500I0J-3502D01*
G01Y268498D01*
G02X1322902Y267081I-3502J1D01*
G03Y266919I183J-81D01*
G02X1323202Y265500I-3202J-1418D01*
G02X1322902Y264081I-3502J-1D01*
G03Y263919I183J-81D01*
G02X1323202Y262500I-3202J-1418D01*
G02X1322902Y261081I-3502J-1D01*
G03Y260919I183J-81D01*
G02X1323202Y259500I-3202J-1418D01*
G02X1322902Y258081I-3502J-1D01*
G03Y257919I183J-81D01*
G02X1323202Y256502I-3202J-1418D01*
G01Y256500D01*
G02X1319700Y252998I-3502J0D01*
G01X1319698D01*
G02X1318281Y253298I1J3502D01*
G03X1318119I-81J-183D01*
G02X1316700Y252998I-1418J3202D01*
G02X1315281Y253298I-1J3502D01*
G03X1315119I-81J-183D01*
G02X1313700Y252998I-1418J3202D01*
G02X1312281Y253298I-1J3502D01*
G03X1312119I-81J-183D01*
G02X1310700Y252998I-1418J3202D01*
G02X1309281Y253298I-1J3502D01*
G03X1309119I-81J-183D01*
G02X1307702Y252998I-1418J3202D01*
G01X1307700D01*
G02X1304198Y256500I0J3502D01*
G01Y256502D01*
G02X1304498Y257919I3502J-1D01*
G03Y258081I-183J81D01*
G02X1304198Y259500I3202J1418D01*
G02X1304498Y260919I3502J1D01*
G03Y261081I-183J81D01*
G02X1304198Y262500I3202J1418D01*
G02X1304498Y263919I3502J1D01*
G03Y264081I-183J81D01*
G02X1304198Y265500I3202J1418D01*
G02X1304498Y266919I3502J1D01*
G03Y267081I-183J81D01*
G02X1304198Y268498I3202J1418D01*
G01Y268500D01*
G02X1307700Y272002I3502J0D01*
G01X1307702D01*
G02X1309119Y271702I-1J-3502D01*
G03X1309281I81J183D01*
G02X1310700Y272002I1418J-3202D01*
G02X1312119Y271702I1J-3502D01*
G03X1312281I81J183D01*
G02X1313700Y272002I1418J-3202D01*
G37*
G36*
G01X1059300Y264998D02*
X1059298D01*
G02X1057550Y265466I1J3502D01*
G03X1057350I-100J-173D01*
G02X1055602Y264998I-1749J3034D01*
G01X1055600D01*
G02Y272002I0J3502D01*
G01X1055602D01*
G02X1057350Y271534I-1J-3502D01*
G03X1057550I100J173D01*
G02X1059298Y272002I1749J-3034D01*
G01X1059300D01*
G02Y264998I0J-3502D01*
G37*
G36*
G01X710084Y257598D02*
X710081D01*
G02X708618Y257919I2J3502D01*
G03X708450I-84J-182D01*
G02X706987Y257598I-1465J3181D01*
G01X706984D01*
G02Y264602I0J3502D01*
G01X706987D01*
G02X708450Y264281I-2J-3502D01*
G03X708618I84J182D01*
G02X710081Y264602I1465J-3181D01*
G01X710084D01*
G02Y257598I0J-3502D01*
G37*
G36*
G01X448738Y249102D02*
G02X450157Y248802I1J-3502D01*
G03X450319I81J183D01*
G02X451738Y249102I1418J-3202D01*
G02X453157Y248802I1J-3502D01*
G03X453319I81J183D01*
G02X454736Y249102I1418J-3202D01*
G01X454738D01*
G02X458240Y245600I0J-3502D01*
G01Y245598D01*
G02X457940Y244181I-3502J1D01*
G03Y244019I183J-81D01*
G02X458240Y242600I-3202J-1418D01*
G02X457940Y241181I-3502J-1D01*
G03Y241019I183J-81D01*
G02X458240Y239600I-3202J-1418D01*
G02X457940Y238181I-3502J-1D01*
G03Y238019I183J-81D01*
G02X458240Y236600I-3202J-1418D01*
G02X457940Y235181I-3502J-1D01*
G03Y235019I183J-81D01*
G02X458240Y233602I-3202J-1418D01*
G01Y233600D01*
G02X454738Y230098I-3502J0D01*
G01X454736D01*
G02X453319Y230398I1J3502D01*
G03X453157I-81J-183D01*
G02X451738Y230098I-1418J3202D01*
G02X450319Y230398I-1J3502D01*
G03X450157I-81J-183D01*
G02X448738Y230098I-1418J3202D01*
G02X447319Y230398I-1J3502D01*
G03X447157I-81J-183D01*
G02X445738Y230098I-1418J3202D01*
G02X444319Y230398I-1J3502D01*
G03X444157I-81J-183D01*
G02X442740Y230098I-1418J3202D01*
G01X442738D01*
G02X439236Y233600I0J3502D01*
G01Y233602D01*
G02X439536Y235019I3502J-1D01*
G03Y235181I-183J81D01*
G02X439236Y236600I3202J1418D01*
G02X439536Y238019I3502J1D01*
G03Y238181I-183J81D01*
G02X439236Y239600I3202J1418D01*
G02X439536Y241019I3502J1D01*
G03Y241181I-183J81D01*
G02X439236Y242600I3202J1418D01*
G02X439536Y244019I3502J1D01*
G03Y244181I-183J81D01*
G02X439236Y245598I3202J1418D01*
G01Y245600D01*
G02X442738Y249102I3502J0D01*
G01X442740D01*
G02X444157Y248802I-1J-3502D01*
G03X444319I81J183D01*
G02X445738Y249102I1418J-3202D01*
G02X447157Y248802I1J-3502D01*
G03X447319I81J183D01*
G02X448738Y249102I1418J-3202D01*
G37*
G36*
G01X658600Y234198D02*
X658598D01*
G02X657181Y234498I1J3502D01*
G03X657019I-81J-183D01*
G02X655602Y234198I-1418J3202D01*
G01X655600D01*
G02Y241202I0J3502D01*
G01X655602D01*
G02X657019Y240902I-1J-3502D01*
G03X657181I81J183D01*
G02X658598Y241202I1418J-3202D01*
G01X658600D01*
G02Y234198I0J-3502D01*
G37*
G36*
G01X1070600Y231502D02*
G02X1072019Y231202I1J-3502D01*
G03X1072181I81J183D01*
G02X1073598Y231502I1418J-3202D01*
G01X1073600D01*
G02Y224498I0J-3502D01*
G01X1073598D01*
G02X1072181Y224798I1J3502D01*
G03X1072019I-81J-183D01*
G02X1070600Y224498I-1418J3202D01*
G02X1067907Y225760I-1J3502D01*
G01X1067879Y225794D01*
X1067799Y225832D01*
X1067401D01*
X1067321Y225794D01*
X1067293Y225760D01*
G02X1064600Y224498I-2692J2240D01*
G02X1063181Y224798I-1J3502D01*
G03X1063019I-81J-183D01*
G02X1061602Y224498I-1418J3202D01*
G01X1061600D01*
G02Y231502I0J3502D01*
G01X1061602D01*
G02X1063019Y231202I-1J-3502D01*
G03X1063181I81J183D01*
G02X1064600Y231502I1418J-3202D01*
G02X1067293Y230240I1J-3502D01*
G01X1067321Y230206D01*
X1067401Y230168D01*
X1067799D01*
X1067879Y230206D01*
X1067907Y230240D01*
G02X1070600Y231502I2692J-2240D01*
G37*
G36*
G01X1313700Y227602D02*
G02X1315119Y227302I1J-3502D01*
G03X1315281I81J183D01*
G02X1316700Y227602I1418J-3202D01*
G02X1318119Y227302I1J-3502D01*
G03X1318281I81J183D01*
G02X1319698Y227602I1418J-3202D01*
G01X1319700D01*
G02X1323202Y224100I0J-3502D01*
G01Y224098D01*
G02X1322902Y222681I-3502J1D01*
G03Y222519I183J-81D01*
G02X1323202Y221100I-3202J-1418D01*
G02X1322902Y219681I-3502J-1D01*
G03Y219519I183J-81D01*
G02X1323202Y218100I-3202J-1418D01*
G02X1322902Y216681I-3502J-1D01*
G03Y216519I183J-81D01*
G02X1323202Y215100I-3202J-1418D01*
G02X1322902Y213681I-3502J-1D01*
G03Y213519I183J-81D01*
G02X1323202Y212102I-3202J-1418D01*
G01Y212100D01*
G02X1319700Y208598I-3502J0D01*
G01X1319698D01*
G02X1318281Y208898I1J3502D01*
G03X1318119I-81J-183D01*
G02X1316700Y208598I-1418J3202D01*
G02X1315281Y208898I-1J3502D01*
G03X1315119I-81J-183D01*
G02X1313700Y208598I-1418J3202D01*
G02X1312281Y208898I-1J3502D01*
G03X1312119I-81J-183D01*
G02X1310700Y208598I-1418J3202D01*
G02X1309281Y208898I-1J3502D01*
G03X1309119I-81J-183D01*
G02X1307702Y208598I-1418J3202D01*
G01X1307700D01*
G02X1304198Y212100I0J3502D01*
G01Y212102D01*
G02X1304498Y213519I3502J-1D01*
G03Y213681I-183J81D01*
G02X1304198Y215100I3202J1418D01*
G02X1304498Y216519I3502J1D01*
G03Y216681I-183J81D01*
G02X1304198Y218100I3202J1418D01*
G02X1304498Y219519I3502J1D01*
G03Y219681I-183J81D01*
G02X1304198Y221100I3202J1418D01*
G02X1304498Y222519I3502J1D01*
G03Y222681I-183J81D01*
G02X1304198Y224098I3202J1418D01*
G01Y224100D01*
G02X1307700Y227602I3502J0D01*
G01X1307702D01*
G02X1309119Y227302I-1J-3502D01*
G03X1309281I81J183D01*
G02X1310700Y227602I1418J-3202D01*
G02X1312119Y227302I1J-3502D01*
G03X1312281I81J183D01*
G02X1313700Y227602I1418J-3202D01*
G37*
G36*
G01X448738Y204702D02*
G02X450157Y204402I1J-3502D01*
G03X450319I81J183D01*
G02X451738Y204702I1418J-3202D01*
G02X453157Y204402I1J-3502D01*
G03X453319I81J183D01*
G02X454736Y204702I1418J-3202D01*
G01X454738D01*
G02X458240Y201200I0J-3502D01*
G01Y201198D01*
G02X457940Y199781I-3502J1D01*
G03Y199619I183J-81D01*
G02X458240Y198200I-3202J-1418D01*
G02X457940Y196781I-3502J-1D01*
G03Y196619I183J-81D01*
G02X458240Y195200I-3202J-1418D01*
G02X457940Y193781I-3502J-1D01*
G03Y193619I183J-81D01*
G02X458240Y192200I-3202J-1418D01*
G02X457940Y190781I-3502J-1D01*
G03Y190619I183J-81D01*
G02X458240Y189202I-3202J-1418D01*
G01Y189200D01*
G02X454738Y185698I-3502J0D01*
G01X454736D01*
G02X453319Y185998I1J3502D01*
G03X453157I-81J-183D01*
G02X451738Y185698I-1418J3202D01*
G02X450319Y185998I-1J3502D01*
G03X450157I-81J-183D01*
G02X448738Y185698I-1418J3202D01*
G02X447319Y185998I-1J3502D01*
G03X447157I-81J-183D01*
G02X445738Y185698I-1418J3202D01*
G02X444319Y185998I-1J3502D01*
G03X444157I-81J-183D01*
G02X442740Y185698I-1418J3202D01*
G01X442738D01*
G02X439236Y189200I0J3502D01*
G01Y189202D01*
G02X439536Y190619I3502J-1D01*
G03Y190781I-183J81D01*
G02X439236Y192200I3202J1418D01*
G02X439536Y193619I3502J1D01*
G03Y193781I-183J81D01*
G02X439236Y195200I3202J1418D01*
G02X439536Y196619I3502J1D01*
G03Y196781I-183J81D01*
G02X439236Y198200I3202J1418D01*
G02X439536Y199619I3502J1D01*
G03Y199781I-183J81D01*
G02X439236Y201198I3202J1418D01*
G01Y201200D01*
G02X442738Y204702I3502J0D01*
G01X442740D01*
G02X444157Y204402I-1J-3502D01*
G03X444319I81J183D01*
G02X445738Y204702I1418J-3202D01*
G02X447157Y204402I1J-3502D01*
G03X447319I81J183D01*
G02X448738Y204702I1418J-3202D01*
G37*
G36*
G01X1307700Y183202D02*
X1307702D01*
G02X1309119Y182902I-1J-3502D01*
G03X1309281I81J183D01*
G02X1310700Y183202I1418J-3202D01*
G02X1312119Y182902I1J-3502D01*
G03X1312281I81J183D01*
G02X1313698Y183202I1418J-3202D01*
G01X1313700D01*
G02X1317149Y180311I0J-3503D01*
G03X1317311Y180149I197J35D01*
G02X1318119Y179902I-612J-3449D01*
G03X1318281I81J183D01*
G02X1319698Y180202I1418J-3202D01*
G01X1319700D01*
G02X1323202Y176700I0J-3502D01*
G01Y176698D01*
G02X1322902Y175281I-3502J1D01*
G03Y175119I183J-81D01*
G02X1323202Y173700I-3202J-1418D01*
G02X1322902Y172281I-3502J-1D01*
G03Y172119I183J-81D01*
G02X1323202Y170700I-3202J-1418D01*
G02X1322902Y169281I-3502J-1D01*
G03Y169119I183J-81D01*
G02X1323202Y167702I-3202J-1418D01*
G01Y167700D01*
G02X1319700Y164198I-3502J0D01*
G01X1319698D01*
G02X1318281Y164498I1J3502D01*
G03X1318119I-81J-183D01*
G02X1316700Y164198I-1418J3202D01*
G02X1315281Y164498I-1J3502D01*
G03X1315119I-81J-183D01*
G02X1313700Y164198I-1418J3202D01*
G02X1312281Y164498I-1J3502D01*
G03X1312119I-81J-183D01*
G02X1310700Y164198I-1418J3202D01*
G02X1309281Y164498I-1J3502D01*
G03X1309119I-81J-183D01*
G02X1307702Y164198I-1418J3202D01*
G01X1307700D01*
G02X1304198Y167700I0J3502D01*
G01Y167702D01*
G02X1304498Y169119I3502J-1D01*
G03Y169281I-183J81D01*
G02X1304198Y170700I3202J1418D01*
G02X1304498Y172119I3502J1D01*
G03Y172281I-183J81D01*
G02X1304198Y173700I3202J1418D01*
G02X1304498Y175119I3502J1D01*
G03Y175281I-183J81D01*
G02X1304198Y176700I3202J1418D01*
G02X1304498Y178119I3502J1D01*
G03Y178281I-183J81D01*
G02X1304198Y179698I3202J1418D01*
G01Y179700D01*
G02X1307700Y183202I3502J0D01*
G37*
G36*
G01X448738Y160302D02*
G02X450157Y160002I1J-3502D01*
G03X450319I81J183D01*
G02X451738Y160302I1418J-3202D01*
G02X453157Y160002I1J-3502D01*
G03X453319I81J183D01*
G02X454736Y160302I1418J-3202D01*
G01X454738D01*
G02X458240Y156800I0J-3502D01*
G01Y156798D01*
G02X457940Y155381I-3502J1D01*
G03Y155219I183J-81D01*
G02X458240Y153800I-3202J-1418D01*
G02X457940Y152381I-3502J-1D01*
G03Y152219I183J-81D01*
G02X458240Y150800I-3202J-1418D01*
G02X457940Y149381I-3502J-1D01*
G03Y149219I183J-81D01*
G02X458240Y147800I-3202J-1418D01*
G02X457940Y146381I-3502J-1D01*
G03Y146219I183J-81D01*
G02X458240Y144802I-3202J-1418D01*
G01Y144800D01*
G02X454738Y141298I-3502J0D01*
G01X454736D01*
G02X453319Y141598I1J3502D01*
G03X453157I-81J-183D01*
G02X451738Y141298I-1418J3202D01*
G02X450319Y141598I-1J3502D01*
G03X450157I-81J-183D01*
G02X448738Y141298I-1418J3202D01*
G02X447319Y141598I-1J3502D01*
G03X447157I-81J-183D01*
G02X445738Y141298I-1418J3202D01*
G02X444319Y141598I-1J3502D01*
G03X444157I-81J-183D01*
G02X442740Y141298I-1418J3202D01*
G01X442738D01*
G02X439236Y144800I0J3502D01*
G01Y144802D01*
G02X439536Y146219I3502J-1D01*
G03Y146381I-183J81D01*
G02X439236Y147800I3202J1418D01*
G02X439536Y149219I3502J1D01*
G03Y149381I-183J81D01*
G02X439236Y150800I3202J1418D01*
G02X439536Y152219I3502J1D01*
G03Y152381I-183J81D01*
G02X439236Y153800I3202J1418D01*
G02X439536Y155219I3502J1D01*
G03Y155381I-183J81D01*
G02X439236Y156798I3202J1418D01*
G01Y156800D01*
G02X442738Y160302I3502J0D01*
G01X442740D01*
G02X444157Y160002I-1J-3502D01*
G03X444319I81J183D01*
G02X445738Y160302I1418J-3202D01*
G02X447157Y160002I1J-3502D01*
G03X447319I81J183D01*
G02X448738Y160302I1418J-3202D01*
G37*
G36*
G01X1313700Y138802D02*
G02X1315119Y138502I1J-3502D01*
G03X1315281I81J183D01*
G02X1316700Y138802I1418J-3202D01*
G02X1318119Y138502I1J-3502D01*
G03X1318281I81J183D01*
G02X1319698Y138802I1418J-3202D01*
G01X1319700D01*
G02X1323202Y135300I0J-3502D01*
G01Y135298D01*
G02X1322902Y133881I-3502J1D01*
G03Y133719I183J-81D01*
G02X1323202Y132300I-3202J-1418D01*
G02X1322902Y130881I-3502J-1D01*
G03Y130719I183J-81D01*
G02X1323202Y129300I-3202J-1418D01*
G02X1322902Y127881I-3502J-1D01*
G03Y127719I183J-81D01*
G02X1323202Y126300I-3202J-1418D01*
G02X1322902Y124881I-3502J-1D01*
G03Y124719I183J-81D01*
G02X1323202Y123302I-3202J-1418D01*
G01Y123300D01*
G02X1319700Y119798I-3502J0D01*
G01X1319698D01*
G02X1318281Y120098I1J3502D01*
G03X1318119I-81J-183D01*
G02X1316700Y119798I-1418J3202D01*
G02X1315281Y120098I-1J3502D01*
G03X1315119I-81J-183D01*
G02X1313700Y119798I-1418J3202D01*
G02X1312281Y120098I-1J3502D01*
G03X1312119I-81J-183D01*
G02X1310700Y119798I-1418J3202D01*
G02X1309281Y120098I-1J3502D01*
G03X1309119I-81J-183D01*
G02X1307702Y119798I-1418J3202D01*
G01X1307700D01*
G02X1304198Y123300I0J3502D01*
G01Y123302D01*
G02X1304498Y124719I3502J-1D01*
G03Y124881I-183J81D01*
G02X1304198Y126300I3202J1418D01*
G02X1304498Y127719I3502J1D01*
G03Y127881I-183J81D01*
G02X1304198Y129300I3202J1418D01*
G02X1304498Y130719I3502J1D01*
G03Y130881I-183J81D01*
G02X1304198Y132300I3202J1418D01*
G02X1304498Y133719I3502J1D01*
G03Y133881I-183J81D01*
G02X1304198Y135298I3202J1418D01*
G01Y135300D01*
G02X1307700Y138802I3502J0D01*
G01X1307702D01*
G02X1309119Y138502I-1J-3502D01*
G03X1309281I81J183D01*
G02X1310700Y138802I1418J-3202D01*
G02X1312119Y138502I1J-3502D01*
G03X1312281I81J183D01*
G02X1313700Y138802I1418J-3202D01*
G37*
G36*
G01X448738Y115902D02*
G02X450157Y115602I1J-3502D01*
G03X450319I81J183D01*
G02X451738Y115902I1418J-3202D01*
G02X453157Y115602I1J-3502D01*
G03X453319I81J183D01*
G02X454736Y115902I1418J-3202D01*
G01X454738D01*
G02X458240Y112400I0J-3502D01*
G01Y112398D01*
G02X457940Y110981I-3502J1D01*
G03Y110819I183J-81D01*
G02X458240Y109400I-3202J-1418D01*
G02X457940Y107981I-3502J-1D01*
G03Y107819I183J-81D01*
G02X458240Y106400I-3202J-1418D01*
G02X457940Y104981I-3502J-1D01*
G03Y104819I183J-81D01*
G02X458240Y103400I-3202J-1418D01*
G02X457940Y101981I-3502J-1D01*
G03Y101819I183J-81D01*
G02X458240Y100402I-3202J-1418D01*
G01Y100400D01*
G02X454738Y96898I-3502J0D01*
G01X454736D01*
G02X453319Y97198I1J3502D01*
G03X453157I-81J-183D01*
G02X451738Y96898I-1418J3202D01*
G02X450319Y97198I-1J3502D01*
G03X450157I-81J-183D01*
G02X448738Y96898I-1418J3202D01*
G02X447319Y97198I-1J3502D01*
G03X447157I-81J-183D01*
G02X445738Y96898I-1418J3202D01*
G02X444319Y97198I-1J3502D01*
G03X444157I-81J-183D01*
G02X442740Y96898I-1418J3202D01*
G01X442738D01*
G02X439236Y100400I0J3502D01*
G01Y100402D01*
G02X439536Y101819I3502J-1D01*
G03Y101981I-183J81D01*
G02X439236Y103400I3202J1418D01*
G02X439536Y104819I3502J1D01*
G03Y104981I-183J81D01*
G02X439236Y106400I3202J1418D01*
G02X439536Y107819I3502J1D01*
G03Y107981I-183J81D01*
G02X439236Y109400I3202J1418D01*
G02X439536Y110819I3502J1D01*
G03Y110981I-183J81D01*
G02X439236Y112398I3202J1418D01*
G01Y112400D01*
G02X442738Y115902I3502J0D01*
G01X442740D01*
G02X444157Y115602I-1J-3502D01*
G03X444319I81J183D01*
G02X445738Y115902I1418J-3202D01*
G02X447157Y115602I1J-3502D01*
G03X447319I81J183D01*
G02X448738Y115902I1418J-3202D01*
G37*
G36*
G01X1313700Y94402D02*
G02X1315119Y94102I1J-3502D01*
G03X1315281I81J183D01*
G02X1316700Y94402I1418J-3202D01*
G02X1318119Y94102I1J-3502D01*
G03X1318281I81J183D01*
G02X1319698Y94402I1418J-3202D01*
G01X1319700D01*
G02X1323202Y90900I0J-3502D01*
G01Y90898D01*
G02X1322902Y89481I-3502J1D01*
G03Y89319I183J-81D01*
G02X1323202Y87900I-3202J-1418D01*
G02X1322902Y86481I-3502J-1D01*
G03Y86319I183J-81D01*
G02X1323202Y84900I-3202J-1418D01*
G02X1322902Y83481I-3502J-1D01*
G03Y83319I183J-81D01*
G02X1323202Y81900I-3202J-1418D01*
G02X1322902Y80481I-3502J-1D01*
G03Y80319I183J-81D01*
G02X1323202Y78902I-3202J-1418D01*
G01Y78900D01*
G02X1319700Y75398I-3502J0D01*
G01X1319698D01*
G02X1318281Y75698I1J3502D01*
G03X1318119I-81J-183D01*
G02X1316700Y75398I-1418J3202D01*
G02X1315281Y75698I-1J3502D01*
G03X1315119I-81J-183D01*
G02X1313700Y75398I-1418J3202D01*
G02X1312281Y75698I-1J3502D01*
G03X1312119I-81J-183D01*
G02X1310700Y75398I-1418J3202D01*
G02X1309281Y75698I-1J3502D01*
G03X1309119I-81J-183D01*
G02X1307702Y75398I-1418J3202D01*
G01X1307700D01*
G02X1304198Y78900I0J3502D01*
G01Y78902D01*
G02X1304498Y80319I3502J-1D01*
G03Y80481I-183J81D01*
G02X1304198Y81900I3202J1418D01*
G02X1304498Y83319I3502J1D01*
G03Y83481I-183J81D01*
G02X1304198Y84900I3202J1418D01*
G02X1304498Y86319I3502J1D01*
G03Y86481I-183J81D01*
G02X1304198Y87900I3202J1418D01*
G02X1304498Y89319I3502J1D01*
G03Y89481I-183J81D01*
G02X1304198Y90898I3202J1418D01*
G01Y90900D01*
G02X1307700Y94402I3502J0D01*
G01X1307702D01*
G02X1309119Y94102I-1J-3502D01*
G03X1309281I81J183D01*
G02X1310700Y94402I1418J-3202D01*
G02X1312119Y94102I1J-3502D01*
G03X1312281I81J183D01*
G02X1313700Y94402I1418J-3202D01*
G37*
G36*
G01X448738Y71502D02*
G02X450157Y71202I1J-3502D01*
G03X450319I81J183D01*
G02X451738Y71502I1418J-3202D01*
G02X453157Y71202I1J-3502D01*
G03X453319I81J183D01*
G02X454736Y71502I1418J-3202D01*
G01X454738D01*
G02X458240Y68000I0J-3502D01*
G01Y67998D01*
G02X457940Y66581I-3502J1D01*
G03Y66419I183J-81D01*
G02X458240Y65000I-3202J-1418D01*
G02X457940Y63581I-3502J-1D01*
G03Y63419I183J-81D01*
G02X458240Y62000I-3202J-1418D01*
G02X457940Y60581I-3502J-1D01*
G03Y60419I183J-81D01*
G02X458240Y59000I-3202J-1418D01*
G02X457940Y57581I-3502J-1D01*
G03Y57419I183J-81D01*
G02X458240Y56002I-3202J-1418D01*
G01Y56000D01*
G02X454738Y52498I-3502J0D01*
G01X454736D01*
G02X453319Y52798I1J3502D01*
G03X453157I-81J-183D01*
G02X451738Y52498I-1418J3202D01*
G02X450319Y52798I-1J3502D01*
G03X450157I-81J-183D01*
G02X448738Y52498I-1418J3202D01*
G02X447319Y52798I-1J3502D01*
G03X447157I-81J-183D01*
G02X445738Y52498I-1418J3202D01*
G02X444319Y52798I-1J3502D01*
G03X444157I-81J-183D01*
G02X442740Y52498I-1418J3202D01*
G01X442738D01*
G02X439236Y56000I0J3502D01*
G01Y56002D01*
G02X439536Y57419I3502J-1D01*
G03Y57581I-183J81D01*
G02X439236Y59000I3202J1418D01*
G02X439536Y60419I3502J1D01*
G03Y60581I-183J81D01*
G02X439236Y62000I3202J1418D01*
G02X439536Y63419I3502J1D01*
G03Y63581I-183J81D01*
G02X439236Y65000I3202J1418D01*
G02X439536Y66419I3502J1D01*
G03Y66581I-183J81D01*
G02X439236Y67998I3202J1418D01*
G01Y68000D01*
G02X442738Y71502I3502J0D01*
G01X442740D01*
G02X444157Y71202I-1J-3502D01*
G03X444319I81J183D01*
G02X445738Y71502I1418J-3202D01*
G02X447157Y71202I1J-3502D01*
G03X447319I81J183D01*
G02X448738Y71502I1418J-3202D01*
G37*
G36*
G01X1406230Y24578D02*
G02X1407649Y24278I1J-3502D01*
G03X1407811I81J183D01*
G02X1409230Y24578I1418J-3202D01*
G02X1410649Y24278I1J-3502D01*
G03X1410811I81J183D01*
G02X1412228Y24578I1418J-3202D01*
G01X1412230D01*
G02X1415732Y21076I0J-3502D01*
G01Y21074D01*
G02X1415432Y19657I-3502J1D01*
G03Y19495I183J-81D01*
G02X1415732Y18076I-3202J-1418D01*
G02X1415432Y16657I-3502J-1D01*
G03Y16495I183J-81D01*
G02X1415732Y15078I-3202J-1418D01*
G01Y15076D01*
G02X1412230Y11574I-3502J0D01*
G01X1412228D01*
G02X1410811Y11874I1J3502D01*
G03X1410649I-81J-183D01*
G02X1409230Y11574I-1418J3202D01*
G02X1407811Y11874I-1J3502D01*
G03X1407649I-81J-183D01*
G02X1406230Y11574I-1418J3202D01*
G02X1404811Y11874I-1J3502D01*
G03X1404649I-81J-183D01*
G02X1403230Y11574I-1418J3202D01*
G02X1401811Y11874I-1J3502D01*
G03X1401649I-81J-183D01*
G02X1400230Y11574I-1418J3202D01*
G02X1398811Y11874I-1J3502D01*
G03X1398649I-81J-183D01*
G02X1397232Y11574I-1418J3202D01*
G01X1397230D01*
G02X1393728Y15076I0J3502D01*
G01Y15078D01*
G02X1394028Y16495I3502J-1D01*
G03Y16657I-183J81D01*
G02X1393728Y18076I3202J1418D01*
G02X1394028Y19495I3502J1D01*
G03Y19657I-183J81D01*
G02X1393728Y21074I3202J1418D01*
G01Y21076D01*
G02X1397230Y24578I3502J0D01*
G01X1397232D01*
G02X1398649Y24278I-1J-3502D01*
G03X1398811I81J183D01*
G02X1400230Y24578I1418J-3202D01*
G02X1401649Y24278I1J-3502D01*
G03X1401811I81J183D01*
G02X1403230Y24578I1418J-3202D01*
G02X1404649Y24278I1J-3502D01*
G03X1404811I81J183D01*
G02X1406230Y24578I1418J-3202D01*
G37*
G36*
G01X334500Y24502D02*
G02X335919Y24202I1J-3502D01*
G03X336081I81J183D01*
G02X337500Y24502I1418J-3202D01*
G02X338919Y24202I1J-3502D01*
G03X339081I81J183D01*
G02X340498Y24502I1418J-3202D01*
G01X340500D01*
G02X344002Y21000I0J-3502D01*
G01Y20998D01*
G02X343702Y19581I-3502J1D01*
G03Y19419I183J-81D01*
G02X344002Y18000I-3202J-1418D01*
G02X343702Y16581I-3502J-1D01*
G03Y16419I183J-81D01*
G02X344002Y15002I-3202J-1418D01*
G01Y15000D01*
G02X340500Y11498I-3502J0D01*
G01X340498D01*
G02X339081Y11798I1J3502D01*
G03X338919I-81J-183D01*
G02X337500Y11498I-1418J3202D01*
G02X336081Y11798I-1J3502D01*
G03X335919I-81J-183D01*
G02X334500Y11498I-1418J3202D01*
G02X333081Y11798I-1J3502D01*
G03X332919I-81J-183D01*
G02X331500Y11498I-1418J3202D01*
G02X330081Y11798I-1J3502D01*
G03X329919I-81J-183D01*
G02X328500Y11498I-1418J3202D01*
G02X327081Y11798I-1J3502D01*
G03X326919I-81J-183D01*
G02X325502Y11498I-1418J3202D01*
G01X325500D01*
G02X321998Y15000I0J3502D01*
G01Y15002D01*
G02X322298Y16419I3502J-1D01*
G03Y16581I-183J81D01*
G02X321998Y18000I3202J1418D01*
G02X322298Y19419I3502J1D01*
G03Y19581I-183J81D01*
G02X321998Y20998I3202J1418D01*
G01Y21000D01*
G02X325500Y24502I3502J0D01*
G01X325502D01*
G02X326919Y24202I-1J-3502D01*
G03X327081I81J183D01*
G02X328500Y24502I1418J-3202D01*
G02X329919Y24202I1J-3502D01*
G03X330081I81J183D01*
G02X331500Y24502I1418J-3202D01*
G02X332919Y24202I1J-3502D01*
G03X333081I81J183D01*
G02X334500Y24502I1418J-3202D01*
G37*
G36*
G01X1438098Y14529D02*
X1438089Y14470D01*
X1438139Y14362D01*
X1438551Y14105D01*
X1438670Y14107D01*
X1438719Y14141D01*
G02X1441417Y14976I2699J-3944D01*
G02Y5418I0J-4779D01*
G02X1436638Y10194I0J4779D01*
G01Y10200D01*
G02X1436639Y10227I4774J-163D01*
G01Y10228D01*
G03X1436520Y10411I-200J0D01*
G01X1436185Y10560D01*
G03X1435969Y10525I-81J-183D01*
G02X1438098Y14529I-4551J4988D01*
G37*
G36*
G01X247547D02*
X247538Y14470D01*
X247588Y14362D01*
X248000Y14105D01*
X248119Y14107D01*
X248168Y14141D01*
G02X250866Y14976I2699J-3944D01*
G01X250868D01*
G02X246088Y10197I-1J-4779D01*
G01Y10228D01*
G03X245969Y10411I-200J0D01*
G01X245634Y10560D01*
G03X245418Y10525I-81J-183D01*
G02X247547Y14529I-4551J4988D01*
G37*
G36*
G01X1225966Y319000D02*
X1275500D01*
G02X1276914Y318414I0J-1999D01*
G01X1279414Y315914D01*
G02X1280000Y314500I-1413J-1414D01*
G01Y51500D01*
G02X1279414Y50086I-1999J0D01*
G01X1276914Y47586D01*
G02X1275500Y47000I-1414J1413D01*
G01X1115567D01*
G02X1114153Y47586I0J1999D01*
G01X1099586Y62153D01*
G02X1099000Y63567I1413J1414D01*
G01Y106106D01*
G03X1098941Y106248I-200J0D01*
G01X1095248Y109941D01*
G03X1095106Y110000I-142J-141D01*
G01X910000D01*
G02X908586Y110586I0J1999D01*
G01X901586Y117586D01*
G02X901000Y119000I1413J1414D01*
G01Y185000D01*
G02X901586Y186414I1999J0D01*
G01X905086Y189914D01*
G02X906500Y190500I1414J-1413D01*
G01X956551D01*
G02X957965Y189914I0J-1999D01*
G01X981058Y166821D01*
G03X981200Y166762I142J141D01*
G01X985094D01*
G03X985279Y166886I0J200D01*
G01X985303Y166942D01*
X985279Y167060D01*
X970074Y182265D01*
G02X969488Y183679I1413J1414D01*
G01Y200875D01*
G02X970074Y202289I1999J0D01*
G01X972219Y204434D01*
G02X973633Y205020I1414J-1413D01*
G01X1013854D01*
G02X1015268Y204434I0J-1999D01*
G01X1017914Y201788D01*
G02X1018500Y200374I-1413J-1414D01*
G01Y180012D01*
G03X1018559Y179870I200J0D01*
G01X1020714Y177714D01*
G02X1020843Y177573I-1409J-1419D01*
G03X1020997Y177500I154J127D01*
G01X1054589D01*
G03X1054731Y177559I0J200D01*
G01X1109786Y232614D01*
G02X1111200Y233200I1414J-1413D01*
G01X1154289D01*
G03X1154431Y233259I0J200D01*
G01X1166141Y244969D01*
G03X1166200Y245111I-141J142D01*
G01Y258700D01*
G02X1166786Y260114I1999J0D01*
G01X1171646Y264974D01*
G03X1171695Y265177I-141J141D01*
G01X1171568Y265570D01*
X1171483Y265643D01*
X1171427Y265652D01*
G02X1168484Y269110I560J3458D01*
G02X1169696Y271760I3503J0D01*
G03X1169765Y271911I-131J151D01*
G01Y272215D01*
G03X1169696Y272366I-200J0D01*
G02X1168484Y275016I2291J2650D01*
G02X1175488I3502J0D01*
G02X1174276Y272366I-3503J0D01*
G03X1174207Y272215I131J-151D01*
G01Y271911D01*
G03X1174276Y271760I200J0D01*
G02X1175488Y269110I-2291J-2650D01*
G01Y269105D01*
G02X1175191Y267696I-3503J2D01*
G01X1175170Y267649D01*
X1175178Y267549D01*
X1175389Y267226D01*
G03X1175556Y267135I168J109D01*
G01X1184429D01*
G03X1184606Y267241I0J200D01*
G02X1190794I3094J-1642D01*
G03X1190971Y267135I177J94D01*
G01X1195493D01*
G03X1195688Y267290I0J200D01*
G02X1196013Y268153I3411J-792D01*
G03Y268343I-176J95D01*
G02X1195596Y270000I3087J1658D01*
G02X1196011Y271654I3504J0D01*
G03X1196010Y271842I-177J93D01*
G02X1195594Y273500I3091J1657D01*
G02X1196010Y275156I3506J0D01*
G03Y275344I-177J94D01*
G02X1195594Y277000I3090J1656D01*
G02X1202606I3506J0D01*
G02X1202190Y275344I-3506J0D01*
G03Y275156I177J-94D01*
G02X1202606Y273500I-3090J-1656D01*
G02X1202190Y271842I-3507J-1D01*
G03X1202189Y271654I176J-95D01*
G02X1202604Y270000I-3089J-1654D01*
G02X1202187Y268343I-3504J1D01*
G03Y268153I176J-95D01*
G02X1202512Y267290I-3086J-1655D01*
G03X1202707Y267135I195J45D01*
G01X1207229D01*
G03X1207406Y267241I0J200D01*
G02X1213594I3094J-1642D01*
G03X1213771Y267135I177J94D01*
G01X1218807D01*
G03X1218949Y267194I0J200D01*
G01X1221256Y269501D01*
G03X1221315Y269643I-141J142D01*
G01Y314349D01*
G02X1221901Y315763I1999J0D01*
G01X1224552Y318414D01*
G02X1225966Y319000I1414J-1413D01*
G37*
G36*
G01X486100D02*
X536375D01*
G02X537789Y318414I0J-1999D01*
G01X540259Y315944D01*
G02X540845Y314530I-1413J-1414D01*
G01Y269824D01*
G03X540904Y269682I200J0D01*
G01X543508Y267078D01*
G03X543650Y267019I142J141D01*
G01X548100D01*
G03X548280Y267132I0J200D01*
G02X554580I3150J-1533D01*
G03X554760Y267019I180J87D01*
G01X559271D01*
X559381Y267109D01*
X559395Y267180D01*
G02X559743Y268153I3435J-680D01*
G03Y268343I-176J95D01*
G02X559326Y270000I3087J1658D01*
G02X559741Y271654I3504J0D01*
G03X559740Y271842I-177J93D01*
G02X559324Y273500I3091J1657D01*
G02X559740Y275156I3506J0D01*
G03Y275344I-177J94D01*
G02X559324Y277000I3090J1656D01*
G02X566336I3506J0D01*
G02X565920Y275344I-3506J0D01*
G03Y275156I177J-94D01*
G02X566336Y273500I-3090J-1656D01*
G02X565920Y271842I-3507J-1D01*
G03X565919Y271654I176J-95D01*
G02X566334Y270000I-3089J-1654D01*
G02X565917Y268343I-3504J1D01*
G03Y268153I176J-95D01*
G02X566265Y267180I-3087J-1653D01*
G01X566279Y267109D01*
X566389Y267019D01*
X573137D01*
G03X573317Y267132I0J200D01*
G02X579617I3150J-1533D01*
G03X579797Y267019I180J87D01*
G01X585308D01*
G02X586722Y266433I0J-1999D01*
G01X633104Y220051D01*
G03X633246Y219992I142J141D01*
G01X691383D01*
G02X692797Y219406I0J-1999D01*
G01X695517Y216686D01*
G02X696103Y215272I-1413J-1414D01*
G01Y210343D01*
G02X695517Y208929I-1999J0D01*
G01X686376Y199788D01*
G02X684962Y199202I-1414J1413D01*
G01X680373D01*
G03X680231Y199143I0J-200D01*
G01X679912Y198824D01*
G03X679853Y198682I141J-142D01*
G01Y172448D01*
G03X679912Y172306I200J0D01*
G01X685477Y166741D01*
G03X685619Y166682I142J141D01*
G01X730158D01*
G03X730348Y166819I0J200D01*
G01X730468Y167179D01*
G03X730399Y167402I-190J63D01*
G01X730398D01*
G02X730186Y167586I1201J1598D01*
G01X715686Y182086D01*
G02X715100Y183500I1413J1414D01*
G01Y200374D01*
G02X715686Y201788I1999J0D01*
G01X718332Y204434D01*
G02X719746Y205020I1414J-1413D01*
G01X759967D01*
G02X761381Y204434I0J-1999D01*
G01X763526Y202289D01*
G02X764112Y200875I-1413J-1414D01*
G01Y183679D01*
G02X763526Y182265I-1999J0D01*
G01X748847Y167586D01*
G02X748635Y167402I-1413J1414D01*
G01X748634D01*
G03X748565Y167179I121J-160D01*
G01X748685Y166819D01*
G03X748875Y166682I190J63D01*
G01X754000D01*
G03X754142Y166741I0J200D01*
G01X777315Y189914D01*
G02X778729Y190500I1414J-1413D01*
G01X827100D01*
G02X828514Y189914I0J-1999D01*
G01X832014Y186414D01*
G02X832600Y185000I-1413J-1414D01*
G01Y119000D01*
G02X832014Y117586I-1999J0D01*
G01X825014Y110586D01*
G02X823600Y110000I-1414J1413D01*
G01X638494D01*
G03X638352Y109941I0J-200D01*
G01X634659Y106248D01*
G03X634600Y106106I141J-142D01*
G01Y63567D01*
G02X634014Y62153I-1999J0D01*
G01X619447Y47586D01*
G02X618033Y47000I-1414J1413D01*
G01X486100D01*
G02X484686Y47586I0J1999D01*
G01X482186Y50086D01*
G02X481600Y51500I1413J1414D01*
G01Y314500D01*
G02X482186Y315914I1999J0D01*
G01X484686Y318414D01*
G02X486100Y319000I1414J-1413D01*
G37*
G36*
G01X704934Y286534D02*
G02X706684Y287002I1749J-3034D01*
G02Y279998I0J-3502D01*
G02X704934Y280466I-1J3502D01*
G03X704734I-100J-173D01*
G02X702984Y279998I-1749J3034D01*
G02Y287002I0J3502D01*
G02X704734Y286534I1J-3502D01*
G03X704934I100J173D01*
G37*
G54D57*
X1565500Y360472D03*
X166785Y200472D03*
X243785D03*
Y280472D03*
X166785D03*
X243785Y360472D03*
X166785D03*
Y440472D03*
X243785D03*
Y520472D03*
X166785D03*
X1565500D03*
X1488500D03*
Y440472D03*
X1565500D03*
X1488500Y200472D03*
X1565500D03*
Y280472D03*
X1488500D03*
Y360472D03*
G54D56*
X1034360Y254000D03*
X725000Y292500D03*
X1320346Y289900D03*
Y245500D03*
X1332671Y190644D03*
X1334140Y146642D03*
X1320346Y112300D03*
Y67900D03*
X1173500Y298500D03*
X1024600Y185000D03*
X704240D03*
X632186Y338917D03*
X623500Y379000D03*
X441938Y309700D03*
Y265300D03*
Y220900D03*
Y176500D03*
Y132100D03*
Y87700D03*
X438100Y214500D03*
X430608Y211389D03*
X438100Y170000D03*
X428277Y167056D03*
G54D59*
X1451417Y10197D03*
X260866D03*
G54D60*
X940197Y200984D03*
X822087D03*
G54D58*
X1565500Y550000D03*
Y470000D03*
Y390000D03*
Y310000D03*
Y230000D03*
X1488500Y550000D03*
Y470000D03*
Y390000D03*
Y310000D03*
Y230000D03*
X243785Y550000D03*
Y470000D03*
Y390000D03*
Y310000D03*
Y230000D03*
X166785Y550000D03*
Y470000D03*
Y390000D03*
Y310000D03*
Y230000D03*
G54D55*
X263780Y659961D03*
X1444882D03*
G54D51*
X1851457Y220433D03*
X1856772Y360433D03*
G54D54*
X300866Y10197D03*
X1491417D03*
G54D52*
X1212478Y300181D03*
X1529100Y78500D03*
X231600Y81000D03*
X19685Y766166D03*
X1854331D03*
G54D50*
X940197Y313484D03*
X822087Y88484D03*
Y313484D03*
X940197Y88484D03*
G54D53*
X1673228Y236614D03*
Y411614D03*
X59055Y236614D03*
Y411594D03*
%LPC*%
G75*
G36*
G01X486511Y180500D02*
X555989D01*
G02X556131Y180441I0J-200D01*
G01X559541Y177031D01*
G02X559600Y176889I-141J-142D01*
G01Y164044D01*
G02X559495Y163867I-200J-1D01*
G03X557653Y160784I1659J-3083D01*
G03X557709Y160159I3502J-1D01*
G01X557718Y160110D01*
X557689Y160017D01*
X557131Y159459D01*
G02X556989Y159400I-142J141D01*
G01X547900D01*
G03X546486Y158814I0J-1999D01*
G01X542086Y154414D01*
G03X541500Y153000I1413J-1414D01*
G01Y133200D01*
G03X542086Y131786I1999J0D01*
G01X543266Y130606D01*
G03X544680Y130020I1414J1413D01*
G01X548775D01*
G02X548919Y129959I0J-200D01*
G03X553941I2511J2441D01*
G02X554085Y130020I144J-139D01*
G01X557169D01*
G02X557311Y129961I0J-200D01*
G01X559541Y127731D01*
G02X559600Y127589I-141J-142D01*
G01Y119287D01*
X559595Y119265D01*
G03X559505Y118477I3412J-789D01*
G03X559595Y117689I3502J1D01*
G01X559600Y117667D01*
Y114933D01*
X559595Y114911D01*
G03X559505Y114123I3412J-789D01*
G03X559595Y113335I3502J1D01*
G01X559600Y113313D01*
Y52911D01*
G02X559541Y52769I-200J0D01*
G01X557831Y51059D01*
G02X557689Y51000I-142J141D01*
G01X487011D01*
G02X486869Y51059I0J200D01*
G01X485659Y52269D01*
G02X485600Y52411I141J142D01*
G01Y179589D01*
G02X485659Y179731I200J0D01*
G01X486369Y180441D01*
G02X486511Y180500I142J-141D01*
G37*
G36*
G01X487011Y315000D02*
X535464D01*
G02X535606Y314941I0J-200D01*
G01X536786Y313761D01*
G02X536845Y313619I-141J-142D01*
G01Y268913D01*
G03X537431Y267499I1999J0D01*
G01X541325Y263605D01*
G03X542739Y263019I1414J1413D01*
G01X548986D01*
G02X549118Y262969I0J-200D01*
G03X551430Y262098I2311J2631D01*
G03X553742Y262969I1J3502D01*
G02X553874Y263019I132J-150D01*
G01X559400D01*
G02X559600Y262819I0J-200D01*
G01Y252487D01*
X559595Y252465D01*
G03X559505Y251677I3412J-789D01*
G03X559595Y250889I3502J1D01*
G01X559600Y250867D01*
Y248133D01*
X559595Y248111D01*
G03X559505Y247323I3412J-789D01*
G03X559595Y246535I3502J1D01*
G01X559600Y246513D01*
Y187911D01*
G02X559541Y187769I-200J0D01*
G01X556331Y184559D01*
G02X556189Y184500I-142J141D01*
G01X486511D01*
G02X486369Y184559I0J200D01*
G01X485659Y185269D01*
G02X485600Y185411I141J142D01*
G01Y313589D01*
G02X485659Y313731I200J0D01*
G01X486869Y314941D01*
G02X487011Y315000I142J-141D01*
G37*
G36*
G01X578911Y263019D02*
X584397D01*
G02X584539Y262960I0J-200D01*
G01X630921Y216578D01*
G03X632335Y215992I1414J1413D01*
G01X690472D01*
G02X690614Y215933I0J-200D01*
G01X692044Y214503D01*
G02X692103Y214361I-141J-142D01*
G01Y211254D01*
G02X692044Y211112I-200J0D01*
G01X684193Y203261D01*
G02X684051Y203202I-142J141D01*
G01X679462D01*
G03X678048Y202616I0J-1999D01*
G01X676439Y201007D01*
G03X675853Y199593I1413J-1414D01*
G01Y171537D01*
G03X676439Y170123I1999J0D01*
G01X683294Y163268D01*
G03X684708Y162682I1414J1413D01*
G01X754911D01*
G03X756325Y163268I0J1999D01*
G01X779498Y186441D01*
G02X779640Y186500I142J-141D01*
G01X826189D01*
G02X826331Y186441I0J-200D01*
G01X828541Y184231D01*
G02X828600Y184089I-141J-142D01*
G01Y119911D01*
G02X828541Y119769I-200J0D01*
G01X822831Y114059D01*
G02X822689Y114000I-142J141D01*
G01X637583D01*
G03X636169Y113414I0J-1999D01*
G01X631186Y108431D01*
G03X630600Y107017I1413J-1414D01*
G01Y64478D01*
G02X630541Y64336I-200J0D01*
G01X617264Y51059D01*
G02X617122Y51000I-142J141D01*
G01X565511D01*
G02X565369Y51059I0J200D01*
G01X563659Y52769D01*
G02X563600Y52911I141J142D01*
G01Y110578D01*
X563688Y110687D01*
X563757Y110702D01*
G03X566509Y114123I-750J3421D01*
G03X565839Y116182I-3502J-1D01*
G02Y116418I162J118D01*
G03X566509Y118477I-2832J2060D01*
G03X563757Y121898I-3502J0D01*
G01X563688Y121913D01*
X563600Y122022D01*
Y127789D01*
G02X563659Y127931I200J0D01*
G01X565689Y129961D01*
G02X565831Y130020I142J-141D01*
G01X571575D01*
G02X571719Y129959I0J-200D01*
G03X576741I2511J2441D01*
G02X576885Y130020I144J-139D01*
G01X580120D01*
G03X581534Y130606I0J1999D01*
G01X583514Y132586D01*
G03X584100Y134000I-1413J1414D01*
G01Y151100D01*
G03X583514Y152514I-1999J0D01*
G01X577214Y158814D01*
G03X575800Y159400I-1414J-1413D01*
G01X568081D01*
G02X567923Y159478I0J200D01*
G01X567700Y159765D01*
X567682Y159855D01*
X567694Y159901D01*
G03X567807Y160784I-3389J882D01*
G03X564305Y164286I-3502J0D01*
G03X564031Y164275I3J-3502D01*
G01X563989Y164272D01*
X563911Y164299D01*
X563664Y164527D01*
G02X563600Y164674I136J147D01*
G01Y243778D01*
X563688Y243887D01*
X563757Y243902D01*
G03X566509Y247323I-750J3421D01*
G03X565839Y249382I-3502J-1D01*
G02Y249618I162J118D01*
G03X566509Y251677I-2832J2060D01*
G03X563757Y255098I-3502J0D01*
G01X563688Y255113D01*
X563600Y255222D01*
Y262819D01*
G02X563800Y263019I200J0D01*
G01X574023D01*
G02X574155Y262969I0J-200D01*
G03X576467Y262098I2311J2631D01*
G03X578779Y262969I1J3502D01*
G02X578911Y263019I132J-150D01*
G37*
G36*
G01X719159Y199605D02*
X720515Y200961D01*
G02X720657Y201020I142J-141D01*
G01X759056D01*
G02X759198Y200961I0J-200D01*
G01X760053Y200106D01*
G02X760112Y199964I-141J-142D01*
G01Y184590D01*
G02X760053Y184448I-200J0D01*
G01X746664Y171059D01*
G02X746522Y171000I-142J141D01*
G01X732511D01*
G02X732369Y171059I0J200D01*
G01X719159Y184269D01*
G02X719100Y184411I141J142D01*
G01Y199463D01*
G02X719159Y199605I200J0D01*
G37*
G36*
G01X1190270Y263135D02*
X1195654D01*
G02X1195796Y263076I0J-200D01*
G01X1197941Y260931D01*
G02X1198000Y260789I-141J-142D01*
G01Y255072D01*
G02X1197880Y254888I-200J-1D01*
G03X1195775Y251677I1397J-3211D01*
G03X1196445Y249618I3502J1D01*
G02Y249382I-162J-118D01*
G03X1195775Y247323I2832J-2060D01*
G03X1197880Y244112I3502J0D01*
G02X1198000Y243928I-80J-183D01*
G01Y165611D01*
G02X1197941Y165469I-200J0D01*
G01X1195917Y163445D01*
X1195887Y163430D01*
G03X1194279Y161822I1538J-3146D01*
G02X1194241Y161769I-179J89D01*
G01X1194031Y161559D01*
G02X1193889Y161500I-142J141D01*
G01X1183800D01*
G03X1182386Y160914I0J-1999D01*
G01X1176414Y154942D01*
G03X1175828Y153528I1413J-1414D01*
G01Y132192D01*
G03X1176414Y130778I1999J0D01*
G01X1176795Y130397D01*
G03X1178209Y129811I1414J1413D01*
G01X1185266D01*
G02X1185397Y129762I0J-200D01*
G03X1190003I2303J2637D01*
G02X1190134Y129811I131J-151D01*
G01X1196878D01*
G02X1197020Y129752I0J-200D01*
G01X1197941Y128831D01*
G02X1198000Y128689I-141J-142D01*
G01Y121872D01*
G02X1197880Y121688I-200J-1D01*
G03X1195775Y118477I1397J-3211D01*
G03X1196445Y116418I3502J1D01*
G02Y116182I-162J-118D01*
G03X1195775Y114123I2832J-2060D01*
G03X1197880Y110912I3502J0D01*
G02X1198000Y110728I-80J-183D01*
G01Y52911D01*
G02X1197941Y52769I-200J0D01*
G01X1196231Y51059D01*
G02X1196089Y51000I-142J141D01*
G01X1116478D01*
G02X1116336Y51059I0J200D01*
G01X1103059Y64336D01*
G02X1103000Y64478I141J142D01*
G01Y107017D01*
G03X1102414Y108431I-1999J0D01*
G01X1097431Y113414D01*
G03X1096017Y114000I-1414J-1413D01*
G01X910911D01*
G02X910769Y114059I0J200D01*
G01X905059Y119769D01*
G02X905000Y119911I141J142D01*
G01Y184089D01*
G02X905059Y184231I200J0D01*
G01X907269Y186441D01*
G02X907411Y186500I142J-141D01*
G01X955640D01*
G02X955782Y186441I0J-200D01*
G01X978875Y163348D01*
G03X980289Y162762I1414J1413D01*
G01X1007447D01*
G03X1008861Y163348I0J1999D01*
G01X1018954Y173441D01*
G02X1019096Y173500I142J-141D01*
G01X1055500D01*
G03X1056914Y174086I0J1999D01*
G01X1111969Y229141D01*
G02X1112111Y229200I142J-141D01*
G01X1155200D01*
G03X1156614Y229786I0J1999D01*
G01X1169614Y242786D01*
G03X1170200Y244200I-1413J1414D01*
G01Y257789D01*
G02X1170259Y257931I200J0D01*
G01X1175404Y263076D01*
G02X1175546Y263135I142J-141D01*
G01X1185130D01*
G02X1185269Y263079I0J-200D01*
G03X1190131I2431J2522D01*
G02X1190270Y263135I139J-144D01*
G37*
G36*
G01X973547Y200106D02*
X974402Y200961D01*
G02X974544Y201020I142J-141D01*
G01X1012943D01*
G02X1013085Y200961I0J-200D01*
G01X1014441Y199605D01*
G02X1014500Y199463I-141J-142D01*
G01Y184411D01*
G02X1014441Y184269I-200J0D01*
G01X1001231Y171059D01*
G02X1001089Y171000I-142J141D01*
G01X987078D01*
G02X986936Y171059I0J200D01*
G01X973547Y184448D01*
G02X973488Y184590I141J142D01*
G01Y199964D01*
G02X973547Y200106I200J0D01*
G37*
G36*
G01X1205411Y180500D02*
X1275089D01*
G02X1275231Y180441I0J-200D01*
G01X1275941Y179731D01*
G02X1276000Y179589I-141J-142D01*
G01Y52411D01*
G02X1275941Y52269I-200J0D01*
G01X1274731Y51059D01*
G02X1274589Y51000I-142J141D01*
G01X1203911D01*
G02X1203769Y51059I0J200D01*
G01X1202059Y52769D01*
G02X1202000Y52911I141J142D01*
G01Y111851D01*
G02X1202042Y111974I200J0D01*
G03X1202779Y114123I-2765J2149D01*
G03X1202109Y116182I-3502J-1D01*
G02Y116418I162J118D01*
G03X1202779Y118477I-2832J2060D01*
G03X1202042Y120626I-3502J0D01*
G02X1202000Y120749I158J123D01*
G01Y128789D01*
G02X1202059Y128931I200J0D01*
G01X1202880Y129752D01*
G02X1203022Y129811I142J-141D01*
G01X1208066D01*
G02X1208197Y129762I0J-200D01*
G03X1212803I2303J2637D01*
G02X1212934Y129811I131J-151D01*
G01X1219382D01*
G03X1220796Y130397I0J1999D01*
G01X1224817Y134418D01*
G03X1225403Y135832I-1413J1414D01*
G01Y153697D01*
G03X1224817Y155111I-1999J0D01*
G01X1219014Y160914D01*
G03X1217600Y161500I-1414J-1413D01*
G01X1204111D01*
G02X1203969Y161559I0J200D01*
G01X1203736Y161792D01*
X1203721Y161822D01*
G03X1202113Y163430I-3146J-1538D01*
G01X1202083Y163445D01*
X1202059Y163469D01*
G02X1202000Y163611I141J142D01*
G01Y177089D01*
G02X1202059Y177231I200J0D01*
G01X1205269Y180441D01*
G02X1205411Y180500I142J-141D01*
G37*
G36*
G01X1226877Y315000D02*
X1274589D01*
G02X1274731Y314941I0J-200D01*
G01X1275941Y313731D01*
G02X1276000Y313589I-141J-142D01*
G01Y185411D01*
G02X1275941Y185269I-200J0D01*
G01X1275231Y184559D01*
G02X1275089Y184500I-142J141D01*
G01X1205611D01*
G02X1205469Y184559I0J200D01*
G01X1202059Y187969D01*
G02X1202000Y188111I141J142D01*
G01Y245051D01*
G02X1202042Y245174I200J0D01*
G03X1202779Y247323I-2765J2149D01*
G03X1202109Y249382I-3502J-1D01*
G02Y249618I162J118D01*
G03X1202779Y251677I-2832J2060D01*
G03X1202042Y253826I-3502J0D01*
G02X1202000Y253949I158J123D01*
G01Y260289D01*
G02X1202059Y260431I200J0D01*
G01X1204704Y263076D01*
G02X1204846Y263135I142J-141D01*
G01X1207930D01*
G02X1208069Y263079I0J-200D01*
G03X1212931I2431J2522D01*
G02X1213070Y263135I139J-144D01*
G01X1219718D01*
G03X1221132Y263721I0J1999D01*
G01X1224729Y267318D01*
G03X1225315Y268732I-1413J1414D01*
G01Y313438D01*
G02X1225374Y313580I200J0D01*
G01X1226735Y314941D01*
G02X1226877Y315000I142J-141D01*
G37*
%LPD*%
G75*
G36*
G01X592781Y243211D02*
G02X593708Y243336I927J-3378D01*
G02X594718Y243187I-1J-3503D01*
G03X594803Y243180I59J191D01*
G02X595276Y243212I472J-3470D01*
G02X595658Y243191I-1J-3502D01*
G03X595735Y243198I21J199D01*
G02X596708Y243336I974J-3365D01*
G02Y236330I0J-3503D01*
G02X596323Y236352I7J3503D01*
G03X596246Y236345I-21J-199D01*
G02X595276Y236208I-970J3365D01*
G02X594268Y236356I-1J3502D01*
G03X594183Y236363I-59J-191D01*
G02X593708Y236330I-480J3470D01*
G02X593467Y236339I10J3503D01*
G03X593400Y236332I-13J-200D01*
G02X592476Y236208I-924J3378D01*
G02Y243212I0J3502D01*
G02X592714Y243204I1J-3502D01*
G03X592781Y243211I13J199D01*
G37*
G36*
G01X41338Y17716D02*
G03X53150I5906J0D01*
G01Y23763D01*
G02X55572Y32155I15747J1D01*
G03X38916I-8328J5246D01*
G02X41338Y23763I-13327J-8392D01*
G01Y17716D01*
G37*
G36*
G01Y330708D02*
G03X53150I5906J0D01*
G01Y336755D01*
G02X55572Y345147I15747J1D01*
G03X38916I-8328J5246D01*
G02X41338Y336755I-13327J-8392D01*
G01Y330708D01*
G37*
G36*
G01X273622Y53148D02*
G03X285434I5906J0D01*
G01Y59195D01*
G02X287856Y67587I15747J1D01*
G03X271200I-8328J5246D01*
G02X273622Y59195I-13327J-8392D01*
G01Y53148D01*
G37*
G36*
G01X309055Y561023D02*
G03X320867I5906J0D01*
G01Y567070D01*
G02X323289Y575462I15747J1D01*
G03X306633I-8328J5246D01*
G02X309055Y567070I-13327J-8392D01*
G01Y561023D01*
G37*
G36*
G01X387796Y344488D02*
G03X399608I5906J0D01*
G01Y350535D01*
G02X402030Y358927I15747J1D01*
G03X385374I-8328J5246D01*
G02X387796Y350535I-13327J-8392D01*
G01Y344488D01*
G37*
G36*
G01X742126Y64961D02*
G03X753938I5906J0D01*
G01Y71008D01*
G02X756360Y79400I15747J1D01*
G03X739704I-8328J5246D01*
G02X742126Y71008I-13327J-8392D01*
G01Y64961D01*
G37*
G36*
G01Y344488D02*
G03X753938I5906J0D01*
G01Y350535D01*
G02X756360Y358927I15747J1D01*
G03X739704I-8328J5246D01*
G02X742126Y350535I-13327J-8392D01*
G01Y344488D01*
G37*
G36*
G01X978346Y64961D02*
G03X990158I5906J0D01*
G01Y71008D01*
G02X992580Y79400I15747J1D01*
G03X975924I-8328J5246D01*
G02X978346Y71008I-13327J-8392D01*
G01Y64961D01*
G37*
G36*
G01Y344488D02*
G03X990158I5906J0D01*
G01Y350535D01*
G02X992580Y358927I15747J1D01*
G03X975924I-8328J5246D01*
G02X978346Y350535I-13327J-8392D01*
G01Y344488D01*
G37*
G36*
G01X1332678D02*
G03X1344490I5906J0D01*
G01Y350535D01*
G02X1346912Y358927I15747J1D01*
G03X1330256I-8328J5246D01*
G02X1332678Y350535I-13327J-8392D01*
G01Y344488D01*
G37*
G36*
G01X1411418Y561023D02*
G03X1423230I5906J0D01*
G01Y567070D01*
G02X1425652Y575462I15747J1D01*
G03X1408996I-8328J5246D01*
G02X1411418Y567070I-13327J-8392D01*
G01Y561023D01*
G37*
G36*
G01X1446850Y53149D02*
G03X1458662I5906J0D01*
G01Y59196D01*
G02X1461084Y67588I15747J1D01*
G03X1444428I-8328J5246D01*
G02X1446850Y59196I-13327J-8392D01*
G01Y53149D01*
G37*
G36*
G01X1679134Y17716D02*
G03X1690946I5906J0D01*
G01Y23763D01*
G02X1693368Y32155I15747J1D01*
G03X1676712I-8328J5246D01*
G02X1679134Y23763I-13327J-8392D01*
G01Y17716D01*
G37*
G36*
G01Y330708D02*
G03X1690946I5906J0D01*
G01Y336755D01*
G02X1693368Y345147I15747J1D01*
G03X1676712I-8328J5246D01*
G02X1679134Y336755I-13327J-8392D01*
G01Y330708D01*
G37*
G36*
G01X1793306Y96457D02*
G03X1805118I5906J0D01*
G01Y102504D01*
G02X1807540Y110896I15747J1D01*
G03X1790884I-8328J5246D01*
G02X1793306Y102504I-13327J-8392D01*
G01Y96457D01*
G37*
G36*
G01Y478346D02*
G03X1805118I5906J0D01*
G01Y484393D01*
G02X1807540Y492785I15747J1D01*
G03X1790884I-8328J5246D01*
G02X1793306Y484393I-13327J-8392D01*
G01Y478346D01*
G37*
G54D17*
X134600Y150000D03*
Y134000D03*
X156785Y101285D03*
X187600Y106500D03*
X176785Y102000D03*
X211425Y106075D03*
X210925Y115575D03*
X317000Y58000D03*
Y74475D03*
Y64500D03*
X325500Y15000D03*
Y18000D03*
Y21000D03*
X340500D03*
Y18000D03*
Y15000D03*
X337500Y21000D03*
Y18000D03*
Y15000D03*
X334500Y21000D03*
Y18000D03*
Y15000D03*
X331500Y21000D03*
Y18000D03*
Y15000D03*
X328500Y21000D03*
Y18000D03*
Y15000D03*
X321500Y74475D03*
Y66500D03*
X325100Y64000D03*
X332500Y63300D03*
X330500Y74476D03*
X326000D03*
X396216Y46875D03*
X428277Y167056D03*
X438100Y170000D03*
X430608Y211389D03*
X438100Y214500D03*
X454738Y56000D03*
X451738D03*
X448738D03*
X445738D03*
X442738D03*
X454738Y68000D03*
Y65000D03*
Y62000D03*
Y59000D03*
X451738D03*
Y62000D03*
Y65000D03*
Y68000D03*
X448738Y59000D03*
Y62000D03*
Y65000D03*
Y68000D03*
X445738Y59000D03*
Y62000D03*
Y65000D03*
Y68000D03*
X442738Y59000D03*
Y62000D03*
Y65000D03*
Y68000D03*
X441938Y87700D03*
X454738Y112400D03*
Y109400D03*
Y106400D03*
Y103400D03*
X451738D03*
Y106400D03*
Y109400D03*
Y112400D03*
X448738Y103400D03*
Y106400D03*
Y109400D03*
Y112400D03*
X445738Y103400D03*
Y106400D03*
Y109400D03*
Y112400D03*
X442738Y103400D03*
Y106400D03*
Y109400D03*
Y112400D03*
X454738Y100400D03*
X451738D03*
X448738D03*
X445738D03*
X442738D03*
X454738Y147800D03*
X451738D03*
X448738D03*
X445738D03*
X442738D03*
X454738Y144800D03*
X451738D03*
X448738D03*
X445738D03*
X442738D03*
X441938Y132100D03*
X454738Y156800D03*
Y153800D03*
Y150800D03*
X451738D03*
Y153800D03*
Y156800D03*
X448738Y150800D03*
Y153800D03*
Y156800D03*
X445738Y150800D03*
Y153800D03*
Y156800D03*
X442738Y150800D03*
Y153800D03*
Y156800D03*
X441938Y176500D03*
X454738Y201200D03*
Y198200D03*
Y195200D03*
Y192200D03*
X451738D03*
Y195200D03*
Y198200D03*
Y201200D03*
X448738Y192200D03*
Y195200D03*
Y198200D03*
Y201200D03*
X445738Y192200D03*
Y195200D03*
Y198200D03*
Y201200D03*
X442738Y192200D03*
Y195200D03*
Y198200D03*
Y201200D03*
X454738Y189200D03*
X451738D03*
X448738D03*
X445738D03*
X442738D03*
X454738Y239600D03*
Y236600D03*
X451738D03*
Y239600D03*
X448738Y236600D03*
Y239600D03*
X445738Y236600D03*
Y239600D03*
X442738Y236600D03*
Y239600D03*
X454738Y233600D03*
X451738D03*
X448738D03*
X445738D03*
X442738D03*
X441938Y220900D03*
X454738Y245600D03*
Y242600D03*
X451738D03*
Y245600D03*
X448738Y242600D03*
Y245600D03*
X445738Y242600D03*
Y245600D03*
X442738Y242600D03*
Y245600D03*
X441938Y265300D03*
X448738Y278000D03*
X451738D03*
X454738D03*
X448738Y290000D03*
Y287000D03*
Y284000D03*
Y281000D03*
X451738Y290000D03*
Y287000D03*
Y284000D03*
Y281000D03*
X454738D03*
Y284000D03*
Y287000D03*
Y290000D03*
X445738D03*
Y287000D03*
Y284000D03*
Y281000D03*
Y278000D03*
X442738Y290000D03*
Y287000D03*
Y284000D03*
Y281000D03*
Y278000D03*
X441938Y309700D03*
X517409Y322000D03*
X506309Y329000D03*
Y322000D03*
X517410Y329000D03*
X551430Y132400D03*
X561155Y160784D03*
X551430Y265600D03*
X563007Y118477D03*
Y114123D03*
X562830Y133300D03*
Y136800D03*
Y140300D03*
Y143800D03*
X574230Y132400D03*
X564305Y160784D03*
X563007Y251677D03*
X576467Y265600D03*
X563007Y247323D03*
X562830Y270000D03*
Y266500D03*
X590298Y282890D03*
X562830Y277000D03*
X571325Y292757D03*
X590298Y276984D03*
X562830Y273500D03*
X571542Y289065D03*
X565091Y302592D03*
X570443Y302702D03*
X595276Y239710D03*
X592476D03*
X620600Y239161D03*
X605800Y256500D03*
X609637Y254523D03*
X605700Y259500D03*
X616184Y267000D03*
X604684D03*
X612684Y297000D03*
X616684Y294500D03*
X602928Y293969D03*
X606084Y293100D03*
X600875Y295937D03*
X616184Y276000D03*
X604684D03*
Y285000D03*
X616184D03*
X590684Y313800D03*
Y310800D03*
X616684Y307975D03*
X622184Y308000D03*
X608259Y305000D03*
X618500Y333500D03*
X639010Y236377D03*
X640684Y264500D03*
Y269000D03*
X645900Y242200D03*
X644502Y246839D03*
X649200Y254500D03*
X650100Y251500D03*
X623684Y281000D03*
X637684Y280575D03*
X629018Y277500D03*
X625684Y273499D03*
X630308Y284500D03*
X632186Y338917D03*
X623500Y379000D03*
X676638Y230894D03*
X658600Y237700D03*
X655600D03*
X681684Y230820D03*
X657259Y263000D03*
X674800Y269600D03*
X660684Y262500D03*
X654100Y263000D03*
X651100Y266000D03*
X679184Y278980D03*
X673684Y280950D03*
X676684D03*
X670184Y288500D03*
X662184Y280500D03*
Y288500D03*
Y284500D03*
X679184Y273190D03*
X676184Y274000D03*
X657500Y330075D03*
X662075Y320000D03*
X675100Y304500D03*
X662125Y308500D03*
X662100Y304500D03*
X658925Y320000D03*
X702223Y197419D03*
X704240Y185000D03*
X689684Y230762D03*
X683592Y259908D03*
X688945Y259761D03*
X695259Y248020D03*
X706984Y261100D03*
X710084D03*
X691794Y261073D03*
X692109Y248020D03*
X686784Y268100D03*
X695584D03*
X698433Y247119D03*
X685884Y297000D03*
X702984Y283500D03*
X706684D03*
X702984Y272400D03*
X706684D03*
X686784Y278000D03*
X695584D03*
X686784Y287900D03*
X695684D03*
X710900Y324100D03*
X696613Y324032D03*
X693904D03*
X691759Y309000D03*
X712000Y215500D03*
X730600Y270000D03*
X727600D03*
X717384Y273400D03*
X719484Y278980D03*
X725000Y292500D03*
X722925Y299500D03*
X719433Y328087D03*
X734500Y307425D03*
X717401Y329996D03*
X770700Y206900D03*
X776000Y206600D03*
X862600Y29500D03*
X867100Y28000D03*
X872533Y29432D03*
X867100Y31500D03*
X887500Y355680D03*
X885100Y361500D03*
X885265Y381000D03*
X878175Y374100D03*
Y364709D03*
X894500Y396500D03*
X954200Y200200D03*
X954600Y207200D03*
X978600Y310955D03*
X1034537Y201437D03*
X1024600Y185000D03*
X1027675Y215000D03*
X1024525D03*
X1034360Y254000D03*
X1032500Y281800D03*
X1029500D03*
X1044900Y278600D03*
X1042800Y273020D03*
X1017300Y322500D03*
X1026270Y303729D03*
X1023492Y346593D03*
X1021414Y355979D03*
X1017300Y385600D03*
X1047163Y197437D03*
X1061600Y228000D03*
X1064600D03*
X1073600D03*
X1070600D03*
X1066600Y264100D03*
X1074430Y256461D03*
X1059300Y268500D03*
X1055600D03*
X1070525Y243000D03*
X1066700Y274000D03*
Y283900D03*
X1052200Y290900D03*
X1055300D03*
X1070490Y290927D03*
X1055600Y279600D03*
X1059300D03*
X1073339Y292239D03*
X1062600Y305000D03*
X1070175Y303980D03*
X1067025D03*
X1072600Y324000D03*
X1064600D03*
X1065800Y339500D03*
X1063300D03*
X1073800D03*
X1071300D03*
X1092100Y263500D03*
X1100100Y243500D03*
X1100500Y263500D03*
X1100100Y247500D03*
X1075500Y264100D03*
X1085600Y271050D03*
X1101500Y271500D03*
X1083100Y273020D03*
X1088079Y274980D03*
X1087100Y282500D03*
X1101600Y289500D03*
X1080600Y294000D03*
X1075500Y274000D03*
Y283900D03*
X1102600Y296000D03*
X1083100Y278810D03*
X1086100Y278000D03*
X1103661Y307700D03*
X1080600Y324000D03*
X1081800Y339500D03*
X1079300D03*
X1086800D03*
X1089300D03*
X1094500Y355600D03*
Y360500D03*
X1129800Y265400D03*
X1131976Y267500D03*
X1108100Y289000D03*
X1121600Y287500D03*
Y283000D03*
X1105025Y289000D03*
X1111100Y291500D03*
Y285000D03*
X1121100Y296000D03*
X1124600Y271425D03*
X1132113Y274500D03*
X1112000Y296000D03*
X1106661Y307700D03*
X1111100Y300500D03*
X1118000Y303500D03*
X1123100Y322500D03*
Y319500D03*
X1130100Y305174D03*
X1130510Y307720D03*
X1123400Y356300D03*
X1132000Y367000D03*
X1145600Y257500D03*
X1149600Y255000D03*
X1160990Y252134D03*
X1146100Y267000D03*
X1157600D03*
X1156200Y258900D03*
X1145600Y244025D03*
X1140100Y244000D03*
X1154025Y247000D03*
X1163266Y255311D03*
X1156584Y292488D03*
X1156509Y295396D03*
X1157600Y276000D03*
X1146100D03*
Y285000D03*
X1157600D03*
X1136000Y278953D03*
X1157800Y312050D03*
X1157138Y303000D03*
X1141600Y312839D03*
X1141500Y347500D03*
X1138500D03*
X1162425Y340500D03*
X1166000Y352500D03*
X1163000D03*
X1153500Y342500D03*
X1187700Y132400D03*
X1197425Y160284D03*
X1187700Y265600D03*
X1171986Y269110D03*
X1173500Y298500D03*
X1196500Y293284D03*
X1171986Y275016D03*
X1176200Y316500D03*
X1173200D03*
X1176000Y350000D03*
X1167800Y355000D03*
X1168200Y349700D03*
X1178900Y359620D03*
X1179500Y350000D03*
Y355000D03*
X1199277Y118477D03*
Y114123D03*
X1210500Y132400D03*
X1199100Y140300D03*
Y133300D03*
Y143800D03*
Y136800D03*
X1200575Y160284D03*
X1199277Y247323D03*
X1210500Y265600D03*
X1199277Y251677D03*
X1199100Y270000D03*
Y266500D03*
X1201500Y293284D03*
X1199100Y277000D03*
Y273500D03*
X1201037Y318912D03*
X1197127Y314264D03*
X1244874Y330000D03*
X1255975D03*
Y337000D03*
X1307700Y78900D03*
Y81900D03*
X1310700D03*
Y78900D03*
X1313700Y81900D03*
Y78900D03*
X1307700Y84900D03*
Y87900D03*
X1310700D03*
Y84900D03*
X1313700Y87900D03*
Y84900D03*
X1307700Y90900D03*
X1310700D03*
X1313700D03*
X1307700Y123300D03*
Y126300D03*
X1310700D03*
Y123300D03*
X1313700Y126300D03*
Y123300D03*
X1307700Y129300D03*
Y132300D03*
Y135300D03*
X1310700D03*
Y132300D03*
Y129300D03*
X1313700Y135300D03*
Y132300D03*
Y129300D03*
Y167700D03*
Y170700D03*
Y173700D03*
Y176700D03*
X1310700Y167700D03*
Y170700D03*
Y173700D03*
Y176700D03*
X1307700D03*
Y173700D03*
Y170700D03*
Y167700D03*
X1313700Y179700D03*
X1310700D03*
X1307700D03*
Y212100D03*
Y215100D03*
X1310700D03*
Y212100D03*
X1313700Y215100D03*
Y212100D03*
X1307700Y218100D03*
Y221100D03*
Y224100D03*
X1310700D03*
Y221100D03*
Y218100D03*
X1313700Y224100D03*
Y221100D03*
Y218100D03*
X1307700Y256500D03*
Y259500D03*
X1310700D03*
Y256500D03*
X1313700Y259500D03*
Y256500D03*
X1307700Y262500D03*
Y265500D03*
Y268500D03*
X1310700D03*
Y265500D03*
Y262500D03*
X1313700Y268500D03*
Y265500D03*
Y262500D03*
X1307700Y300900D03*
Y303900D03*
X1310700D03*
Y300900D03*
X1313700Y303900D03*
Y300900D03*
X1307700Y306900D03*
Y309900D03*
Y312900D03*
X1310700D03*
Y309900D03*
Y306900D03*
X1313700Y309900D03*
Y306900D03*
X1316700Y81900D03*
Y78900D03*
X1319700Y81900D03*
Y78900D03*
X1316700Y87900D03*
Y84900D03*
X1319700Y87900D03*
Y84900D03*
X1320346Y67900D03*
X1316700Y90900D03*
X1319700D03*
X1320346Y112300D03*
X1316700Y126300D03*
Y123300D03*
X1319700Y126300D03*
Y123300D03*
X1316700Y135300D03*
Y132300D03*
Y129300D03*
X1319700Y135300D03*
Y132300D03*
Y129300D03*
X1334140Y146642D03*
X1319700Y167700D03*
Y170700D03*
Y173700D03*
Y176700D03*
X1316700Y167700D03*
Y170700D03*
Y173700D03*
Y176700D03*
X1324100Y150500D03*
X1320346Y156700D03*
X1324100Y194900D03*
X1332671Y190644D03*
X1320346Y201100D03*
X1316700Y215100D03*
Y212100D03*
X1319700Y215100D03*
Y212100D03*
X1316700Y224100D03*
Y221100D03*
Y218100D03*
X1319700Y224100D03*
Y221100D03*
Y218100D03*
X1316700Y259500D03*
Y256500D03*
X1319700Y259500D03*
Y256500D03*
X1316700Y268500D03*
Y265500D03*
Y262500D03*
X1319700Y268500D03*
Y265500D03*
Y262500D03*
X1320346Y245500D03*
Y289900D03*
X1316700Y303900D03*
Y300900D03*
X1319700Y303900D03*
Y300900D03*
X1316700Y306900D03*
X1406230Y21076D03*
Y18076D03*
Y15076D03*
X1403230Y21076D03*
Y18076D03*
Y15076D03*
X1400230Y21076D03*
Y18076D03*
Y15076D03*
X1397230D03*
Y18076D03*
Y21076D03*
X1412230D03*
Y18076D03*
Y15076D03*
X1409230Y21076D03*
Y18076D03*
Y15076D03*
X1498180Y63500D03*
X1494728Y83500D03*
X1490000Y80500D03*
X1499228Y74500D03*
X1494728Y66500D03*
X1490228D03*
X1505100Y64500D03*
X1503728Y74477D03*
X1527100Y98925D03*
X1524600Y111500D03*
X1551000Y96500D03*
X1567500Y67000D03*
X1597100Y145000D03*
Y126000D03*
X1614100Y125000D03*
X1618100Y148925D03*
X1647800Y83200D03*
Y77200D03*
Y80200D03*
X1622295Y114940D03*
X1625370Y103940D03*
X1642037Y104134D03*
X1643537Y101434D03*
X1640037D03*
X1638537Y104134D03*
X1645537D03*
X1647037Y101434D03*
X1632336Y109117D03*
X1631323Y115140D03*
X1624500Y142500D03*
Y146000D03*
X1622295Y118940D03*
X1644917Y124581D03*
X1641932Y122969D03*
X1650117Y180000D03*
X1636600Y173500D03*
X1622100Y155931D03*
X1626000Y163500D03*
Y167500D03*
X1626925Y156000D03*
X1629000Y175000D03*
X1624000Y189000D03*
X1642000Y184500D03*
X1645000D03*
X1660250Y113860D03*
X1657050Y116760D03*
Y113860D03*
X1660250Y116760D03*
X1669800Y120400D03*
X1675800D03*
X1651037Y99734D03*
X1658500Y138000D03*
X1672800Y120400D03*
X1656657Y127365D03*
X1651325Y125076D03*
X1676350Y160251D03*
X1672050Y181550D03*
X1657500Y191500D03*
X1664000Y202500D03*
X1661500Y199000D03*
X1667600Y198500D03*
X1658000Y179500D03*
X1654000Y192500D03*
X1660000Y193500D03*
X1692000Y76570D03*
X1695500Y76500D03*
X1706100Y92000D03*
X1701350Y114250D03*
X1696600Y119000D03*
X1682500Y121825D03*
X1697976Y148000D03*
X1690100Y127375D03*
X1688100Y145560D03*
X1705100Y140500D03*
X1707100Y142500D03*
X1685000Y133000D03*
X1702600Y171500D03*
X1697976Y164500D03*
Y159000D03*
Y175500D03*
Y170000D03*
Y153500D03*
X1680000Y156500D03*
X1688100Y173060D03*
Y162060D03*
X1709600Y158000D03*
X1701000Y159000D03*
Y164500D03*
X1685975Y186500D03*
X1701100Y182000D03*
X1688100Y184220D03*
X1697975Y181000D03*
X1704600Y201500D03*
X1718675Y88000D03*
X1719075Y107016D03*
Y112000D03*
X1718675Y99000D03*
Y93500D03*
X1713524Y109500D03*
Y114500D03*
X1721685Y95940D03*
X1738000Y124500D03*
X1721000Y142525D03*
X1714100Y144925D03*
X1713525Y134500D03*
Y129500D03*
X1713524Y119500D03*
X1727100Y164280D03*
X1715525Y168500D03*
Y153000D03*
X1722063Y156962D03*
X1726099Y153000D03*
X1720524Y175000D03*
X1717600Y158000D03*
X1728475Y175000D03*
X1731925Y199000D03*
X1714175Y187000D03*
X1721500Y205000D03*
X1721600Y194760D03*
Y198500D03*
X1767525Y114016D03*
X1759600Y114500D03*
X1767425Y107000D03*
X1761600Y124524D03*
X1764000Y142525D03*
X1767425Y137000D03*
X1768500Y142525D03*
X1764100Y119500D03*
X1764000Y158025D03*
X1759925Y178900D03*
X1768500Y158025D03*
X1763925Y170984D03*
Y155484D03*
X1766925Y181500D03*
X1769425Y203000D03*
X1754925D03*
X1750563Y198000D03*
X1747925Y204000D03*
X1751600Y258000D03*
Y255500D03*
X1740600Y258000D03*
Y255500D03*
Y248000D03*
Y250500D03*
Y253000D03*
X1751600D03*
Y250500D03*
Y248000D03*
X1766432Y250301D03*
Y247301D03*
X1769300Y329400D03*
Y340600D03*
X1769692Y334649D03*
X1767700Y346200D03*
X1767600Y350000D03*
X1772975Y109500D03*
Y104500D03*
X1773076Y117500D03*
X1773000Y142525D03*
X1773500Y129500D03*
X1772975Y124500D03*
X1773000Y158000D03*
X1772600Y177300D03*
X1800100Y187500D03*
X1778000Y189500D03*
X1789600Y247000D03*
X1783932Y250357D03*
Y247357D03*
X1775432Y250357D03*
Y247357D03*
X1795600Y308000D03*
X1777375Y356300D03*
X1777383Y352305D03*
X1784035Y389535D03*
X1781535D03*
X1784035Y386935D03*
X1781535D03*
X1778838Y389508D03*
Y386908D03*
X1781535Y402935D03*
X1784035D03*
X1778838Y402908D03*
X1781535Y405535D03*
X1784035D03*
X1778838Y405508D03*
X1817500Y188000D03*
X1809600Y195000D03*
X1811500Y186000D03*
X1842164Y419238D03*
X1847164D03*
X1837164D03*
X1852164D03*
X1842164Y432338D03*
X1847164Y430568D03*
X1852164Y435538D03*
X1837164Y428238D03*
G54D20*
X166785Y230000D03*
Y310000D03*
Y390000D03*
Y470000D03*
Y550000D03*
X243785Y230000D03*
Y310000D03*
Y390000D03*
Y470000D03*
Y550000D03*
X1488500Y230000D03*
Y310000D03*
Y390000D03*
Y470000D03*
Y550000D03*
X1565500Y230000D03*
Y310000D03*
Y390000D03*
Y470000D03*
Y550000D03*
G54D47*
X1846142Y270433D03*
X1856772D03*
X1846142Y280433D03*
Y290433D03*
Y300433D03*
X1856772D03*
Y290433D03*
Y280433D03*
X1848957Y324213D03*
X1843957Y329213D03*
X1848957Y314213D03*
X1843957Y319213D03*
X1853957Y329213D03*
Y319213D03*
X1848957Y334213D03*
Y344213D03*
X1843957Y339213D03*
Y349213D03*
X1853957D03*
Y339213D03*
X1858957Y344213D03*
Y334213D03*
G54D15*
X45275Y236614D03*
Y411594D03*
X72835Y236614D03*
X68898Y226771D03*
X59055Y222834D03*
X49212Y226771D03*
X68898Y246457D03*
X49212D03*
X59055Y250394D03*
X68898Y421437D03*
X72835Y411594D03*
X68898Y401751D03*
X59055Y397814D03*
X49212Y401751D03*
Y421437D03*
X59055Y425374D03*
X1673228Y222834D03*
X1663385Y226771D03*
X1659448Y236614D03*
X1663385Y246457D03*
X1673228Y250394D03*
Y397834D03*
X1663385Y401771D03*
X1659448Y411614D03*
X1663385Y421457D03*
X1673228Y425394D03*
X1687008Y236614D03*
X1683071Y226771D03*
Y246457D03*
Y421457D03*
X1687008Y411614D03*
X1683071Y401771D03*
G54D42*
X1642915Y111950D03*
X1639372Y114450D03*
X1646458Y111950D03*
X1642915Y114450D03*
X1639372Y111950D03*
X1646458Y114450D03*
X1650002Y111950D03*
Y114450D03*
G54D28*
X468946Y338216D03*
X465946D03*
X468946Y341216D03*
X465946D03*
X458946Y338216D03*
X455946D03*
X458946Y341216D03*
X455946D03*
Y357216D03*
X458946D03*
X468946Y357016D03*
X465946D03*
X471946Y338216D03*
Y341216D03*
X481446Y338216D03*
X478446D03*
X481446Y341216D03*
X478446D03*
X484446Y338216D03*
Y341216D03*
X471946Y357016D03*
X528084Y77900D03*
Y74900D03*
Y71900D03*
X525084Y77900D03*
Y74900D03*
Y71900D03*
X522084Y77900D03*
Y74900D03*
Y71900D03*
X525084Y116300D03*
X522084D03*
X528084D03*
X525084Y122300D03*
X522084D03*
X525084Y119300D03*
X522084D03*
X528084Y122300D03*
Y119300D03*
X525084Y166700D03*
X522084D03*
X525084Y160700D03*
Y163700D03*
X522084D03*
Y160700D03*
Y205100D03*
Y208100D03*
X525084D03*
Y205100D03*
X522084Y211100D03*
X525084D03*
X522084Y249500D03*
Y252500D03*
X525084D03*
Y249500D03*
X522084Y255500D03*
X525084D03*
X528084Y252500D03*
Y249500D03*
Y255500D03*
Y299900D03*
X525084D03*
X522084D03*
X528084Y296900D03*
X525084D03*
X522084D03*
X528084Y293900D03*
X525084D03*
X522084D03*
X531084Y77900D03*
Y74900D03*
Y71900D03*
Y299900D03*
Y296900D03*
Y293900D03*
X586184Y117800D03*
X583184D03*
X580184D03*
X586184Y114800D03*
X583184D03*
X580184D03*
X586184Y111800D03*
X583184D03*
X580184D03*
X586184Y108800D03*
X583184D03*
X580184D03*
X586184Y105800D03*
X583184D03*
X580184D03*
Y126800D03*
X583184D03*
X586184D03*
Y123800D03*
X583184D03*
X580184D03*
X586184Y120800D03*
X583184D03*
X580184D03*
X583184Y239000D03*
X580184D03*
X583184Y242000D03*
X580184D03*
X583184Y254000D03*
Y251000D03*
Y248000D03*
Y245000D03*
X580184D03*
Y248000D03*
Y251000D03*
Y254000D03*
X583184Y260000D03*
Y257000D03*
X580184D03*
Y260000D03*
X620466Y246839D03*
X664484Y212500D03*
X666984D03*
X672484D03*
X674984D03*
X679484D03*
X681984D03*
X685484D03*
X687984D03*
X1240200Y77900D03*
Y74900D03*
Y71900D03*
Y68900D03*
Y65900D03*
X1237200D03*
Y68900D03*
Y71900D03*
Y74900D03*
Y77900D03*
X1234200Y65900D03*
Y68900D03*
Y71900D03*
Y74900D03*
Y77900D03*
X1231200Y65900D03*
Y68900D03*
Y71900D03*
Y74900D03*
Y77900D03*
X1234200Y116300D03*
Y113300D03*
Y110300D03*
X1237200Y116300D03*
Y113300D03*
Y110300D03*
X1240200D03*
Y113300D03*
Y116300D03*
X1234200Y122300D03*
Y119300D03*
X1237200Y122300D03*
Y119300D03*
X1240200D03*
Y122300D03*
X1237200Y166700D03*
Y163700D03*
Y160700D03*
Y157700D03*
Y154700D03*
X1240200D03*
Y157700D03*
Y160700D03*
Y163700D03*
Y166700D03*
X1237200Y208100D03*
X1240200D03*
X1237200Y211100D03*
X1240200D03*
X1234200Y252500D03*
X1237200D03*
X1234200Y255500D03*
X1237200D03*
X1240200Y252500D03*
Y255500D03*
Y299900D03*
Y296900D03*
X1237200D03*
Y299900D03*
X1234200Y296900D03*
Y299900D03*
X1231200Y296900D03*
Y299900D03*
X1657050Y102380D03*
X1685100Y127500D03*
X1692600Y135975D03*
X1751600Y238000D03*
Y235500D03*
X1740600D03*
Y238000D03*
X1751600Y233000D03*
X1740600D03*
X1766447Y239798D03*
Y242798D03*
X1751600Y240500D03*
X1740600D03*
X1783947Y239798D03*
Y242798D03*
X1775447Y239798D03*
Y242798D03*
X1789600Y243500D03*
G54D29*
X649059Y314000D03*
X1491918Y107773D03*
Y110773D03*
Y113773D03*
Y104773D03*
X1488918D03*
Y113773D03*
Y110773D03*
Y107773D03*
X1485918Y104773D03*
Y113773D03*
Y110773D03*
Y107773D03*
X1482918Y104773D03*
Y113773D03*
Y110773D03*
Y107773D03*
X1618800Y76700D03*
X1615800Y82700D03*
Y79700D03*
Y76700D03*
X1618800Y79700D03*
Y82700D03*
X1727200Y104500D03*
X1728600Y387500D03*
X1731100D03*
X1733600D03*
X1770575Y137000D03*
X1762454Y320347D03*
X1742109Y345235D03*
Y342435D03*
X1747416Y348293D03*
X1747909Y345335D03*
Y342535D03*
X1744909Y345335D03*
Y342535D03*
X1742109Y339635D03*
Y336835D03*
Y334035D03*
X1747909Y339735D03*
Y336935D03*
Y334135D03*
X1744909Y339735D03*
Y336935D03*
Y334135D03*
X1767151Y333311D03*
X1777532Y328322D03*
X1777459Y332322D03*
X1777383Y348288D03*
G54D34*
X802087Y200984D03*
X792087D03*
X822087D03*
X812087D03*
X920197D03*
X910197D03*
X940197D03*
X930197D03*
G54D37*
X825900Y362200D03*
Y372200D03*
X866400Y362200D03*
Y382200D03*
X906900Y362200D03*
Y372200D03*
G54D21*
X163878Y601693D03*
X156004D03*
X163878Y609567D03*
Y617441D03*
Y625315D03*
Y633189D03*
X156004Y609567D03*
Y617441D03*
Y625315D03*
Y633189D03*
X163878Y641063D03*
Y648937D03*
Y656811D03*
X156004Y641063D03*
Y648937D03*
Y656811D03*
X163878Y664685D03*
X156004D03*
X1587107Y601693D03*
Y609567D03*
Y617441D03*
Y625315D03*
Y633189D03*
Y641063D03*
Y648937D03*
Y656811D03*
Y664685D03*
X1594981Y601693D03*
Y609567D03*
Y617441D03*
Y625315D03*
Y633189D03*
Y641063D03*
Y648937D03*
Y656811D03*
Y664685D03*
G54D31*
X681498Y575042D03*
Y565042D03*
X681604Y593187D03*
Y603187D03*
X997833Y575042D03*
Y565042D03*
Y593187D03*
Y603187D03*
G54D43*
X1848583Y99212D03*
X1848582Y481693D03*
G54D18*
X137303Y601693D03*
Y609567D03*
Y617441D03*
Y625315D03*
Y633189D03*
Y641063D03*
Y648937D03*
Y656811D03*
Y664685D03*
X145177Y601693D03*
Y609567D03*
Y617441D03*
Y625315D03*
Y633189D03*
Y641063D03*
Y648937D03*
Y656811D03*
Y664685D03*
X192126Y633189D03*
Y625315D03*
Y617441D03*
X200000Y633189D03*
Y625315D03*
Y617441D03*
X215748Y633189D03*
Y625315D03*
Y617441D03*
X223622Y633189D03*
Y625315D03*
Y617441D03*
X250866Y10197D03*
X255906Y617441D03*
X248032D03*
X255906Y625315D03*
Y633189D03*
X248032D03*
Y625315D03*
X279646Y23012D03*
Y13012D03*
X274646Y18012D03*
X284646Y8012D03*
X274646D03*
X260866Y10197D03*
X279528Y617441D03*
X271654D03*
X279528Y625315D03*
Y633189D03*
X271654D03*
Y625315D03*
X289646Y23012D03*
Y13012D03*
X295276Y617441D03*
Y625315D03*
Y633189D03*
X303150D03*
Y625315D03*
Y617441D03*
X1437008D03*
X1429134D03*
X1437008Y625315D03*
Y633189D03*
X1429134D03*
Y625315D03*
X1465197Y18012D03*
Y8012D03*
X1451417Y10197D03*
X1441417D03*
X1460630Y617441D03*
X1452756D03*
X1460630Y625315D03*
Y633189D03*
X1452756D03*
Y625315D03*
X1480197Y23012D03*
X1470197D03*
X1480197Y13012D03*
X1470197D03*
X1475197Y8012D03*
X1476378Y617441D03*
Y625315D03*
Y633189D03*
X1484252D03*
Y625315D03*
Y617441D03*
X1508661Y633189D03*
Y625315D03*
Y617441D03*
X1516535Y633189D03*
Y625315D03*
Y617441D03*
X1532283Y633189D03*
Y625315D03*
Y617441D03*
X1540157Y633189D03*
Y625315D03*
Y617441D03*
X1576280Y601693D03*
X1568406D03*
X1576280Y609567D03*
Y617441D03*
Y625315D03*
Y633189D03*
X1568406Y609567D03*
Y617441D03*
Y625315D03*
Y633189D03*
X1576280Y641063D03*
Y648937D03*
Y656811D03*
X1568406Y641063D03*
Y648937D03*
Y656811D03*
X1576280Y664685D03*
X1568406D03*
G54D45*
X1846142Y230433D03*
Y240433D03*
X1856772D03*
Y230433D03*
X1846142Y250433D03*
Y260433D03*
X1856772D03*
Y250433D03*
X1858957Y324213D03*
Y314213D03*
G54D38*
X825900Y382200D03*
X906900D03*
G54D41*
X1011017Y598187D03*
G54D40*
Y570042D03*
G54D25*
X207874Y639095D03*
X1524409D03*
G54D14*
X47244Y17716D03*
Y330708D03*
X279528Y53148D03*
X314961Y561023D03*
X393702Y344488D03*
X748032Y64961D03*
Y344488D03*
X984252Y64961D03*
Y344488D03*
X1338584D03*
X1417324Y561023D03*
X1452756Y53149D03*
X1685040Y17716D03*
Y330708D03*
X1799212Y96457D03*
Y478346D03*
G54D27*
X287402Y628465D03*
X263780Y659961D03*
X1468504Y628465D03*
X1444882Y659961D03*
G54D10*
X19685Y-774040D03*
Y766166D03*
X240866Y15512D03*
X300866Y10197D03*
X566575Y463701D03*
D03*
D03*
X1431417Y15512D03*
X1491417Y10197D03*
X1854331Y-774040D03*
Y766166D03*
G54D46*
X1851457Y220433D03*
X1856772Y360433D03*
G54D23*
X231600Y81000D03*
X1212478Y300181D03*
X1529100Y78500D03*
G54D35*
X822087Y88484D03*
Y313484D03*
X940197Y88484D03*
Y313484D03*
G54D22*
X192126Y656811D03*
Y648937D03*
Y664685D03*
X215748Y656811D03*
Y648937D03*
X223622Y656811D03*
Y648937D03*
X200000Y656811D03*
Y648937D03*
X215748Y664685D03*
X223622D03*
X200000D03*
X255906Y648937D03*
X248032D03*
X255906Y656811D03*
X248032D03*
X255906Y664685D03*
X248032D03*
X279528Y648937D03*
X271654D03*
X279528Y656811D03*
X271654D03*
X279528Y664685D03*
X271654D03*
X303150Y648937D03*
X295276D03*
X303150Y656811D03*
X295276D03*
X303150Y664685D03*
X295276D03*
X1437008Y648937D03*
X1429134D03*
X1437008Y656811D03*
X1429134D03*
X1437008Y664685D03*
X1429134D03*
X1460630Y648937D03*
X1452756D03*
X1460630Y656811D03*
X1452756D03*
X1460630Y664685D03*
X1452756D03*
X1484252Y648937D03*
X1476378D03*
X1484252Y656811D03*
X1476378D03*
X1484252Y664685D03*
X1476378D03*
X1508661Y656811D03*
Y648937D03*
X1516535Y656811D03*
Y648937D03*
X1508661Y664685D03*
X1516535D03*
X1532283Y656811D03*
Y648937D03*
X1540157Y656811D03*
Y648937D03*
X1532283Y664685D03*
X1540157D03*
G54D26*
X250866Y20827D03*
X284646Y18012D03*
X260866Y20827D03*
X1451417D03*
X1441417D03*
X1475197Y18012D03*
G54D24*
X225829Y103412D03*
Y99503D03*
X225953Y95780D03*
X225891Y92305D03*
X229829Y103412D03*
X233329D03*
X237329D03*
X229829Y99503D03*
X233329D03*
X237329D03*
X229953Y95780D03*
X233453D03*
X237453D03*
X229891Y92305D03*
X233391D03*
X237391D03*
X622288Y235790D03*
X624788D03*
X1635000Y152925D03*
X1733600Y397500D03*
X1731100D03*
X1728600D03*
G54D11*
X3018Y23930D03*
X10493Y5830D03*
X3018Y43930D03*
Y83930D03*
Y63930D03*
Y103930D03*
Y143930D03*
Y123930D03*
Y163930D03*
Y203930D03*
Y183930D03*
Y223930D03*
Y263930D03*
Y243930D03*
Y283930D03*
Y323930D03*
Y303930D03*
Y343930D03*
Y383930D03*
Y363930D03*
Y403930D03*
Y443930D03*
Y423930D03*
Y463930D03*
Y503930D03*
Y483930D03*
Y523930D03*
Y563930D03*
Y543930D03*
Y583930D03*
X15642Y619715D03*
X3018Y603930D03*
X30709Y3014D03*
X35455Y620194D03*
X75455D03*
X55455D03*
X81406Y3042D03*
X101406D03*
X95455Y620194D03*
X121406Y3042D03*
X137355Y120500D03*
X114923Y623982D03*
X124901Y640105D03*
X161406Y3042D03*
X141406D03*
X154778Y672779D03*
X181406Y3042D03*
X194778Y672779D03*
X174778D03*
X201406Y3042D03*
X221406D03*
X205061Y85500D03*
Y79000D03*
Y75000D03*
Y71500D03*
Y67500D03*
Y89500D03*
Y93000D03*
Y97000D03*
X200600Y109059D03*
X205100Y123000D03*
X214778Y672779D03*
X254778D03*
X234778D03*
X274778D03*
X314766Y39211D03*
X317766D03*
X311956Y651522D03*
X294778Y672779D03*
X323766Y39211D03*
X320766D03*
X324000Y77000D03*
X321000Y63000D03*
X345412Y435017D03*
Y455017D03*
Y475017D03*
Y495017D03*
Y515017D03*
Y535017D03*
Y555017D03*
Y575017D03*
Y595017D03*
X342119Y613510D03*
X331285Y620008D03*
X369192Y38417D03*
X372192D03*
X378192D03*
X375192D03*
X362127Y406608D03*
X350024Y418335D03*
X408100Y180100D03*
Y224500D03*
X399680Y402510D03*
X379680D03*
X419680D03*
X459680D03*
X439680D03*
X498923Y37456D03*
X495923D03*
X492923D03*
X489923D03*
X479680Y402510D03*
X501923Y37456D03*
X504923D03*
X510923D03*
X507923D03*
X528084Y68900D03*
Y65900D03*
X525084Y68900D03*
Y65900D03*
X522084Y68900D03*
Y65900D03*
X525084Y113300D03*
Y110300D03*
X522084Y113300D03*
Y110300D03*
X528084Y113300D03*
Y110300D03*
X525084Y157700D03*
Y154700D03*
X522084Y157700D03*
Y154700D03*
Y199100D03*
Y202100D03*
X525084Y199100D03*
Y202100D03*
X522084Y243500D03*
Y246500D03*
X525084Y243500D03*
Y246500D03*
X528084Y243500D03*
Y246500D03*
Y290900D03*
Y287900D03*
X525084D03*
Y290900D03*
X522084D03*
Y287900D03*
X499680Y402510D03*
X519680D03*
X531084Y68900D03*
Y65900D03*
Y290900D03*
Y287900D03*
X539680Y402510D03*
X559680D03*
X579680D03*
X601675Y305575D03*
X619680Y402510D03*
X599680D03*
X645784Y43500D03*
X648784D03*
X645784Y40500D03*
X648784D03*
X645784Y99000D03*
X648784D03*
X645784Y96000D03*
X648784D03*
X641000Y261500D03*
X639680Y402510D03*
X651784Y43500D03*
Y40500D03*
X657784D03*
X654784D03*
X657784Y43500D03*
X654784D03*
X651784Y99000D03*
Y96000D03*
X657784D03*
X654784D03*
X657784Y99000D03*
X654784D03*
X659000Y284000D03*
X671000Y315760D03*
X668000Y311500D03*
X663500D03*
X657500Y326925D03*
X659680Y402510D03*
X679680D03*
X693863Y189760D03*
X688900Y184260D03*
X704200Y206569D03*
X699680Y402510D03*
X736554Y131056D03*
Y128056D03*
X739554Y131056D03*
Y128056D03*
X742554D03*
X732100Y185000D03*
X729100D03*
X726100D03*
X720100D03*
X723100D03*
X726100Y188000D03*
X729100D03*
X732100D03*
X723100D03*
X720100D03*
X726000Y231500D03*
X729000D03*
X723000D03*
X720000D03*
X732000D03*
Y228500D03*
X720000D03*
X723000D03*
X726000D03*
X729000D03*
X719500Y315500D03*
X734500Y310575D03*
X739680Y402510D03*
X719680D03*
X742554Y131056D03*
X749600Y185000D03*
X752600D03*
X755600D03*
X758600D03*
X746600Y188000D03*
X758600D03*
X755600D03*
X752600D03*
X749600D03*
X746600Y185000D03*
X758500Y231500D03*
X746500D03*
X755500D03*
X752500D03*
X749500D03*
X746500Y228500D03*
X755500D03*
X752500D03*
X749500D03*
X758500D03*
X759680Y402510D03*
X779680D03*
X799680D03*
X819680D03*
X839680D03*
X859680D03*
X880500Y369500D03*
X879680Y402510D03*
X919680D03*
X899680D03*
X939680D03*
X983500Y185000D03*
Y188000D03*
X980500Y185000D03*
X974500D03*
X977500D03*
X980500Y188000D03*
X977500D03*
X974500D03*
Y231500D03*
X977500D03*
X983500D03*
X980500D03*
X983500Y228500D03*
X980500D03*
X977500D03*
X974500D03*
X959680Y402510D03*
X979680D03*
X990954Y131056D03*
Y128056D03*
X993954Y131056D03*
Y128056D03*
X996954D03*
Y131056D03*
X986500Y185000D03*
Y188000D03*
X1004000Y185000D03*
X1001000Y188000D03*
X1004000D03*
X1007000Y185000D03*
X1010000D03*
X1013000D03*
Y188000D03*
X1010000D03*
X1007000D03*
X1001000Y185000D03*
X1004000Y231500D03*
X1007000D03*
X1010000D03*
X1001000D03*
X986500D03*
X1013000D03*
X986500Y228500D03*
X1013000D03*
X1004000D03*
X1007000D03*
X1010000D03*
X1001000D03*
X999680Y402510D03*
X1030100Y207500D03*
X1039680Y402510D03*
X1019680D03*
X1074500Y43500D03*
Y99000D03*
X1059680Y402510D03*
X1077500Y43500D03*
Y40500D03*
X1074500D03*
X1080500D03*
X1083500D03*
X1086500D03*
X1080500Y43500D03*
X1083500D03*
X1086500D03*
X1077500Y99000D03*
Y96000D03*
X1074500D03*
X1080500D03*
X1083500D03*
X1086500D03*
X1080500Y99000D03*
X1083500D03*
X1086500D03*
X1101500Y268500D03*
X1079680Y402510D03*
X1099680D03*
X1118500Y283000D03*
X1106000Y364500D03*
X1112500Y364700D03*
X1122000Y366240D03*
X1119680Y402510D03*
X1155366Y38982D03*
X1152366D03*
X1158366D03*
X1161366D03*
X1143500Y251500D03*
X1141600Y305161D03*
X1154600Y321050D03*
X1143100Y322500D03*
Y320000D03*
X1147000Y342500D03*
X1135000Y366500D03*
X1139000D03*
X1159680Y402510D03*
X1139680D03*
X1176100Y105800D03*
Y108800D03*
X1182100Y105800D03*
Y108800D03*
X1179100D03*
Y105800D03*
X1176100Y111800D03*
Y114800D03*
Y117800D03*
X1182100Y111800D03*
Y114800D03*
Y117800D03*
X1179100D03*
Y114800D03*
Y111800D03*
X1176100Y126800D03*
Y123800D03*
Y120800D03*
X1182100Y126800D03*
Y123800D03*
Y120800D03*
X1179100D03*
Y123800D03*
Y126800D03*
X1176100Y239000D03*
X1171600Y238000D03*
X1179100Y239000D03*
X1182100D03*
X1176100Y254000D03*
Y251000D03*
Y248000D03*
Y245000D03*
Y257000D03*
Y260000D03*
Y242000D03*
X1171600Y241500D03*
X1179100Y242000D03*
Y260000D03*
Y257000D03*
Y245000D03*
Y248000D03*
Y251000D03*
Y254000D03*
X1182100D03*
Y251000D03*
Y248000D03*
Y245000D03*
Y257000D03*
Y260000D03*
Y242000D03*
X1165575Y340500D03*
X1171700Y349900D03*
X1178500Y368740D03*
X1179680Y402510D03*
X1223866Y38482D03*
X1220866D03*
X1225930Y359148D03*
X1199680Y402510D03*
X1219680D03*
X1226866Y38482D03*
X1229866D03*
X1237200Y205100D03*
Y202100D03*
Y199100D03*
X1240200D03*
Y202100D03*
Y205100D03*
X1234200Y249500D03*
Y246500D03*
Y243500D03*
X1237200Y249500D03*
Y246500D03*
Y243500D03*
X1240200D03*
Y246500D03*
Y249500D03*
Y293900D03*
Y290900D03*
Y287900D03*
X1237200D03*
Y290900D03*
Y293900D03*
X1234200Y287900D03*
Y290900D03*
Y293900D03*
X1231200D03*
Y290900D03*
Y287900D03*
X1242930Y359148D03*
Y356148D03*
X1245930Y359148D03*
Y356148D03*
X1248930Y359148D03*
Y356148D03*
X1231930D03*
Y359148D03*
X1228930Y356148D03*
Y359148D03*
X1225930Y356148D03*
X1253930Y379648D03*
X1250930D03*
X1247930D03*
X1239680Y402510D03*
X1264366Y38482D03*
X1261366D03*
X1267366D03*
X1270366D03*
X1260340Y359284D03*
Y356284D03*
X1263340Y359284D03*
Y356284D03*
X1266340Y359284D03*
Y356284D03*
X1286113Y378312D03*
X1265340Y379784D03*
X1268340D03*
X1271340D03*
X1259680Y402510D03*
X1279680D03*
X1313366Y38482D03*
X1307366D03*
X1310366D03*
X1286113Y375312D03*
X1289113Y378312D03*
Y375312D03*
X1292113Y378312D03*
Y375312D03*
Y372312D03*
X1289113D03*
X1299680Y402510D03*
X1316366Y38482D03*
X1339680Y402510D03*
X1319680D03*
X1355310Y38893D03*
X1352310D03*
X1349310D03*
X1358310D03*
X1355100Y160000D03*
X1355000Y204400D03*
X1359620Y402940D03*
X1386882Y434539D03*
Y454539D03*
Y474539D03*
Y494539D03*
Y514539D03*
Y534539D03*
Y554539D03*
Y574539D03*
Y594539D03*
X1389643Y612723D03*
X1403035Y620181D03*
X1422310Y40481D03*
X1419310D03*
X1416310D03*
X1425310D03*
X1420335Y635388D03*
Y655388D03*
X1428754Y670547D03*
X1445829Y672778D03*
X1465829D03*
X1490000Y84000D03*
X1485829Y672778D03*
X1508460Y3003D03*
X1527100Y108500D03*
X1505829Y672778D03*
X1525829D03*
X1548460Y3003D03*
X1528460D03*
X1531600Y96941D03*
X1545829Y672778D03*
X1588460Y3003D03*
X1568460D03*
X1565829Y672778D03*
X1585829D03*
X1608460Y3003D03*
X1609100Y85500D03*
Y82000D03*
X1606100Y85500D03*
Y82000D03*
X1609100Y69500D03*
Y66000D03*
Y62500D03*
X1606100Y69500D03*
Y66000D03*
Y62500D03*
X1602100Y85500D03*
Y82000D03*
Y69500D03*
Y66000D03*
Y62500D03*
X1594930Y115000D03*
X1614100Y110000D03*
Y115000D03*
X1609100Y89000D03*
X1606100D03*
X1602100D03*
X1614100Y120000D03*
Y130000D03*
X1613527Y627220D03*
X1607226Y650448D03*
X1602599Y667628D03*
X1648460Y3003D03*
X1628460D03*
X1629870Y104240D03*
X1647837Y121812D03*
X1638707Y132954D03*
X1623100Y172500D03*
Y178000D03*
X1631585Y188777D03*
X1628658Y620261D03*
X1648675Y620226D03*
X1662000Y106000D03*
X1649197Y132915D03*
X1650990Y122034D03*
X1667000Y138000D03*
X1649500Y173398D03*
X1668075Y189500D03*
X1679176Y194760D03*
X1652600Y212000D03*
X1668675Y620226D03*
X1708460Y3003D03*
X1702525Y129500D03*
X1685976Y148000D03*
Y164500D03*
Y159000D03*
Y153500D03*
Y175500D03*
Y170000D03*
X1701100Y178500D03*
X1685976Y181000D03*
X1702075Y205500D03*
X1688692Y620191D03*
X1708692D03*
X1729255Y25347D03*
Y45347D03*
X1732786Y58461D03*
X1729411Y143661D03*
X1720100Y179500D03*
X1729411Y159161D03*
X1733500Y173760D03*
X1712000Y153000D03*
X1738740Y191500D03*
X1729000Y183500D03*
X1724824Y205276D03*
X1711025Y187000D03*
X1729275Y562751D03*
Y542751D03*
Y582751D03*
Y602751D03*
X1753635Y69037D03*
X1764000Y107000D03*
X1763500Y113000D03*
X1763075Y178900D03*
X1767075Y155484D03*
X1769476Y168500D03*
X1754260Y187260D03*
X1768000D03*
X1746000Y191240D03*
X1751289Y345227D03*
X1747416Y351817D03*
X1747235Y355989D03*
Y359564D03*
Y363689D03*
Y367264D03*
Y371389D03*
Y374964D03*
X1755454Y515746D03*
X1793635Y69037D03*
X1773635D03*
X1773500Y121000D03*
X1772500Y174000D03*
X1770075Y181500D03*
X1776100Y361500D03*
Y371500D03*
Y368500D03*
X1776140Y364405D03*
X1775454Y515746D03*
X1813635Y69037D03*
X1815454Y515746D03*
X1853635Y69037D03*
X1833635D03*
X1844500Y416500D03*
X1847500Y437000D03*
X1835454Y515746D03*
X1855509Y515697D03*
X1871008Y117112D03*
X1871009Y93913D03*
X1871008Y137112D03*
Y177112D03*
Y157112D03*
Y197112D03*
Y237112D03*
Y217112D03*
Y257112D03*
Y297112D03*
Y277112D03*
Y317112D03*
Y357112D03*
Y337112D03*
Y377112D03*
Y417112D03*
Y397112D03*
Y437112D03*
Y477112D03*
Y457112D03*
Y497112D03*
G54D33*
X802087Y145984D03*
X792087D03*
X802087Y135984D03*
X792087D03*
X802087Y180984D03*
X792087D03*
X802087Y170984D03*
X792087D03*
X802087Y230984D03*
X792087D03*
X802087Y220984D03*
X792087D03*
X802087Y265984D03*
X792087D03*
X802087Y255984D03*
X792087D03*
X822087Y145984D03*
X812087D03*
X822087Y135984D03*
X812087D03*
X822087Y180984D03*
X812087D03*
X822087Y170984D03*
X812087D03*
X822087Y230984D03*
X812087D03*
X822087Y220984D03*
X812087D03*
X822087Y265984D03*
X812087D03*
X822087Y255984D03*
X812087D03*
X920197Y145984D03*
X910197D03*
X920197Y135984D03*
X910197D03*
X920197Y180984D03*
X910197D03*
X920197Y170984D03*
X910197D03*
X920197Y230984D03*
X910197D03*
X920197Y220984D03*
X910197D03*
X920197Y265984D03*
X910197D03*
X920197Y255984D03*
X910197D03*
X940197Y145984D03*
X930197D03*
X940197Y135984D03*
X930197D03*
X940197Y180984D03*
X930197D03*
X940197Y170984D03*
X930197D03*
X940197Y230984D03*
X930197D03*
X940197Y220984D03*
X930197D03*
X940197Y265984D03*
X930197D03*
X940197Y255984D03*
X930197D03*
G54D36*
X822087Y88484D03*
Y313484D03*
X940197Y88484D03*
Y313484D03*
G54D16*
X59055Y236614D03*
Y411594D03*
X1673228Y236614D03*
Y411614D03*
G54D44*
X1835739Y99212D03*
X1835738Y481693D03*
G54D12*
X32284Y541339D03*
X59055Y498032D03*
X1673228D03*
X1700000Y541339D03*
G54D39*
X866400Y372200D03*
G54D30*
X668314Y570042D03*
G54D32*
X668420Y598187D03*
%LPC*%
G75*
G54D19*
X166785Y200472D03*
Y280472D03*
Y360472D03*
Y440472D03*
Y520472D03*
X243785Y200472D03*
Y280472D03*
Y360472D03*
Y440472D03*
Y520472D03*
X1488500Y200472D03*
Y280472D03*
Y360472D03*
Y440472D03*
Y520472D03*
X1565500Y200472D03*
Y280472D03*
Y360472D03*
Y440472D03*
Y520472D03*
G54D48*
G01X166785Y200472D02*
X163614Y197301D01*
G01X169956Y203643D02*
X166785Y200472D01*
G01D02*
X163614Y203643D01*
G01X169956Y197301D02*
X166785Y200472D01*
G01Y280472D02*
X163614Y277301D01*
G01X169956Y283643D02*
X166785Y280472D01*
G01D02*
X163614Y283643D01*
G01X169956Y277301D02*
X166785Y280472D01*
G01Y360472D02*
X163614Y357301D01*
G01X169956Y363643D02*
X166785Y360472D01*
G01D02*
X163614Y363643D01*
G01X169956Y357301D02*
X166785Y360472D01*
G01Y440472D02*
X163614Y437301D01*
G01X169956Y443643D02*
X166785Y440472D01*
G01D02*
X163614Y443643D01*
G01X169956Y437301D02*
X166785Y440472D01*
G01X169956Y517301D02*
X166785Y520472D01*
G01D02*
X163614Y523643D01*
G01X169956D02*
X166785Y520472D01*
G01D02*
X163614Y517301D01*
G01X243785Y200472D02*
X240614Y197301D01*
G01X246956Y203643D02*
X243785Y200472D01*
G01D02*
X240614Y203643D01*
G01X246956Y197301D02*
X243785Y200472D01*
G01Y280472D02*
X240614Y277301D01*
G01X246956Y283643D02*
X243785Y280472D01*
G01D02*
X240614Y283643D01*
G01X246956Y277301D02*
X243785Y280472D01*
G01Y360472D02*
X240614Y357301D01*
G01X246956Y363643D02*
X243785Y360472D01*
G01D02*
X240614Y363643D01*
G01X246956Y357301D02*
X243785Y360472D01*
G01Y440472D02*
X240614Y437301D01*
G01X246956Y443643D02*
X243785Y440472D01*
G01D02*
X240614Y443643D01*
G01X246956Y437301D02*
X243785Y440472D01*
G01Y520472D02*
X240614Y517301D01*
G01X246956Y523643D02*
X243785Y520472D01*
G01D02*
X240614Y523643D01*
G01X246956Y517301D02*
X243785Y520472D01*
G01X1488500Y200472D02*
X1485329Y197301D01*
G01X1491671Y203643D02*
X1488500Y200472D01*
G01D02*
X1485329Y203643D01*
G01X1491671Y197301D02*
X1488500Y200472D01*
G01Y280472D02*
X1485329Y277301D01*
G01X1491671Y283643D02*
X1488500Y280472D01*
G01D02*
X1485329Y283643D01*
G01X1491671Y277301D02*
X1488500Y280472D01*
G01Y360472D02*
X1485329Y357301D01*
G01X1491671Y363643D02*
X1488500Y360472D01*
G01D02*
X1485329Y363643D01*
G01X1491671Y357301D02*
X1488500Y360472D01*
G01Y440472D02*
X1485329Y437301D01*
G01X1491671Y443643D02*
X1488500Y440472D01*
G01D02*
X1485329Y443643D01*
G01X1491671Y437301D02*
X1488500Y440472D01*
G01Y520472D02*
X1485329Y517301D01*
G01X1491671Y523643D02*
X1488500Y520472D01*
G01D02*
X1485329Y523643D01*
G01X1491671Y517301D02*
X1488500Y520472D01*
G01X1565500Y200472D02*
X1562329Y197301D01*
G01X1568671Y203643D02*
X1565500Y200472D01*
G01D02*
X1562329Y203643D01*
G01X1568671Y197301D02*
X1565500Y200472D01*
G01Y280472D02*
X1562329Y277301D01*
G01X1568671Y283643D02*
X1565500Y280472D01*
G01D02*
X1562329Y283643D01*
G01X1568671Y277301D02*
X1565500Y280472D01*
G01Y360472D02*
X1562329Y357301D01*
G01X1568671Y363643D02*
X1565500Y360472D01*
G01D02*
X1562329Y363643D01*
G01X1568671Y357301D02*
X1565500Y360472D01*
G01Y440472D02*
X1562329Y437301D01*
G01X1568671Y443643D02*
X1565500Y440472D01*
G01D02*
X1562329Y443643D01*
G01X1568671Y437301D02*
X1565500Y440472D01*
G01Y520472D02*
X1562329Y517301D01*
G01X1568671Y523643D02*
X1565500Y520472D01*
G01D02*
X1562329Y523643D01*
G01X1568671Y517301D02*
X1565500Y520472D01*
G54D49*
G01X-457143Y-1211429D02*
Y2242857D01*
X4308572D01*
Y-1211429D01*
X-457143D01*
G01X37000Y-995000D02*
Y-1070000D01*
X537000D01*
Y-995000D01*
X37000D01*
G01X49000Y-1060000D02*
Y-1065000D01*
G01X47543Y-1060000D02*
X50457D01*
G01X55367Y-1065000D02*
X52833D01*
Y-1060000D01*
X55367D01*
G01X54353Y-1062417D02*
X52833D01*
G01X57933Y-1060000D02*
Y-1065000D01*
X60467D01*
G01X64300Y-1065167D02*
X64173Y-1065083D01*
Y-1064917D01*
X64300Y-1064833D01*
X64427Y-1064917D01*
Y-1065083D01*
X64300Y-1065167D01*
G01Y-1062917D02*
X64173Y-1062833D01*
Y-1062667D01*
X64300Y-1062583D01*
X64427Y-1062667D01*
Y-1062833D01*
X64300Y-1062917D01*
G01X69083Y-1066667D02*
X68450Y-1065833D01*
X68133Y-1065000D01*
Y-1061667D01*
X68450Y-1060833D01*
X69083Y-1060000D01*
G01X74500D02*
X73993Y-1060167D01*
X73613Y-1060583D01*
X73360Y-1061083D01*
X73170Y-1061750D01*
X73107Y-1062500D01*
X73170Y-1063250D01*
X73360Y-1063917D01*
X73613Y-1064417D01*
X73993Y-1064833D01*
X74500Y-1065000D01*
X75007Y-1064833D01*
X75387Y-1064417D01*
X75640Y-1063917D01*
X75830Y-1063250D01*
X75893Y-1062500D01*
X75830Y-1061750D01*
X75640Y-1061083D01*
X75387Y-1060583D01*
X75007Y-1060167D01*
X74500Y-1060000D01*
G01X78207Y-1064000D02*
X78587Y-1064583D01*
X79093Y-1064917D01*
X79663Y-1065000D01*
X80170Y-1064917D01*
X80677Y-1064500D01*
X80993Y-1064000D01*
X81057Y-1063500D01*
X80930Y-1062917D01*
X80487Y-1062500D01*
X80043Y-1062333D01*
X79473D01*
G01X80043D02*
X80423Y-1062083D01*
X80740Y-1061667D01*
X80867Y-1061167D01*
X80740Y-1060667D01*
X80423Y-1060250D01*
X79853Y-1060000D01*
X79283Y-1060083D01*
X78713Y-1060417D01*
G01X85017Y-1066667D02*
X85650Y-1065833D01*
X85967Y-1065000D01*
Y-1061667D01*
X85650Y-1060833D01*
X85017Y-1060000D01*
G01X88407Y-1064000D02*
X88787Y-1064583D01*
X89293Y-1064917D01*
X89863Y-1065000D01*
X90370Y-1064917D01*
X90877Y-1064500D01*
X91193Y-1064000D01*
X91257Y-1063500D01*
X91130Y-1062917D01*
X90687Y-1062500D01*
X90243Y-1062333D01*
X89673D01*
G01X90243D02*
X90623Y-1062083D01*
X90940Y-1061667D01*
X91067Y-1061167D01*
X90940Y-1060667D01*
X90623Y-1060250D01*
X90053Y-1060000D01*
X89483Y-1060083D01*
X88913Y-1060417D01*
G01X93697Y-1060833D02*
X94077Y-1060333D01*
X94520Y-1060083D01*
X95027Y-1060000D01*
X95660Y-1060167D01*
X96103Y-1060583D01*
X96230Y-1061083D01*
X96167Y-1061583D01*
X95913Y-1062000D01*
X94647Y-1062833D01*
X94077Y-1063417D01*
X93697Y-1064250D01*
X93570Y-1065000D01*
X96230D01*
G01X99873D02*
X100000Y-1063917D01*
X100190Y-1063000D01*
X100443Y-1062167D01*
X100760Y-1061250D01*
X101267Y-1060000D01*
X98733D01*
G01X104277Y-1063333D02*
X105923D01*
G01X108997Y-1060833D02*
X109377Y-1060333D01*
X109820Y-1060083D01*
X110327Y-1060000D01*
X110960Y-1060167D01*
X111403Y-1060583D01*
X111530Y-1061083D01*
X111467Y-1061583D01*
X111213Y-1062000D01*
X109947Y-1062833D01*
X109377Y-1063417D01*
X108997Y-1064250D01*
X108870Y-1065000D01*
X111530D01*
G01X113907Y-1064000D02*
X114287Y-1064583D01*
X114793Y-1064917D01*
X115363Y-1065000D01*
X115870Y-1064917D01*
X116377Y-1064500D01*
X116693Y-1064000D01*
X116757Y-1063500D01*
X116630Y-1062917D01*
X116187Y-1062500D01*
X115743Y-1062333D01*
X115173D01*
G01X115743D02*
X116123Y-1062083D01*
X116440Y-1061667D01*
X116567Y-1061167D01*
X116440Y-1060667D01*
X116123Y-1060250D01*
X115553Y-1060000D01*
X114983Y-1060083D01*
X114413Y-1060417D01*
G01X121160Y-1065000D02*
Y-1060000D01*
X118817Y-1063583D01*
X121983D01*
G01X124107Y-1064250D02*
X124487Y-1064667D01*
X124930Y-1064917D01*
X125500Y-1065000D01*
X126070Y-1064833D01*
X126513Y-1064500D01*
X126830Y-1063917D01*
X126893Y-1063250D01*
X126767Y-1062583D01*
X126450Y-1062167D01*
X126007Y-1061833D01*
X125563Y-1061750D01*
X125120Y-1061833D01*
X124550Y-1062167D01*
X124740Y-1060000D01*
X126450D01*
G01X134497Y-1065000D02*
Y-1060000D01*
X136903D01*
G01X136017Y-1062417D02*
X134497D01*
G01X139217Y-1065000D02*
X140800Y-1060000D01*
X142383Y-1065000D01*
G01X141813Y-1063250D02*
X139787D01*
G01X144570Y-1065000D02*
X147230Y-1060000D01*
G01X144570D02*
X147230Y-1065000D01*
G01X151000Y-1065167D02*
X150873Y-1065083D01*
Y-1064917D01*
X151000Y-1064833D01*
X151127Y-1064917D01*
Y-1065083D01*
X151000Y-1065167D01*
G01Y-1062917D02*
X150873Y-1062833D01*
Y-1062667D01*
X151000Y-1062583D01*
X151127Y-1062667D01*
Y-1062833D01*
X151000Y-1062917D01*
G01X155783Y-1066667D02*
X155150Y-1065833D01*
X154833Y-1065000D01*
Y-1061667D01*
X155150Y-1060833D01*
X155783Y-1060000D01*
G01X161200D02*
X160693Y-1060167D01*
X160313Y-1060583D01*
X160060Y-1061083D01*
X159870Y-1061750D01*
X159807Y-1062500D01*
X159870Y-1063250D01*
X160060Y-1063917D01*
X160313Y-1064417D01*
X160693Y-1064833D01*
X161200Y-1065000D01*
X161707Y-1064833D01*
X162087Y-1064417D01*
X162340Y-1063917D01*
X162530Y-1063250D01*
X162593Y-1062500D01*
X162530Y-1061750D01*
X162340Y-1061083D01*
X162087Y-1060583D01*
X161707Y-1060167D01*
X161200Y-1060000D01*
G01X164907Y-1064000D02*
X165287Y-1064583D01*
X165793Y-1064917D01*
X166363Y-1065000D01*
X166870Y-1064917D01*
X167377Y-1064500D01*
X167693Y-1064000D01*
X167757Y-1063500D01*
X167630Y-1062917D01*
X167187Y-1062500D01*
X166743Y-1062333D01*
X166173D01*
G01X166743D02*
X167123Y-1062083D01*
X167440Y-1061667D01*
X167567Y-1061167D01*
X167440Y-1060667D01*
X167123Y-1060250D01*
X166553Y-1060000D01*
X165983Y-1060083D01*
X165413Y-1060417D01*
G01X171717Y-1066667D02*
X172350Y-1065833D01*
X172667Y-1065000D01*
Y-1061667D01*
X172350Y-1060833D01*
X171717Y-1060000D01*
G01X175107Y-1064000D02*
X175487Y-1064583D01*
X175993Y-1064917D01*
X176563Y-1065000D01*
X177070Y-1064917D01*
X177577Y-1064500D01*
X177893Y-1064000D01*
X177957Y-1063500D01*
X177830Y-1062917D01*
X177387Y-1062500D01*
X176943Y-1062333D01*
X176373D01*
G01X176943D02*
X177323Y-1062083D01*
X177640Y-1061667D01*
X177767Y-1061167D01*
X177640Y-1060667D01*
X177323Y-1060250D01*
X176753Y-1060000D01*
X176183Y-1060083D01*
X175613Y-1060417D01*
G01X180523Y-1064417D02*
X180967Y-1064833D01*
X181473Y-1065000D01*
X181980Y-1064833D01*
X182423Y-1064333D01*
X182740Y-1063583D01*
X182867Y-1062833D01*
Y-1061917D01*
X182740Y-1061167D01*
X182423Y-1060500D01*
X182043Y-1060167D01*
X181600Y-1060000D01*
X181093Y-1060167D01*
X180713Y-1060500D01*
X180460Y-1061000D01*
X180333Y-1061667D01*
X180460Y-1062250D01*
X180777Y-1062833D01*
X181157Y-1063167D01*
X181600Y-1063250D01*
X182107Y-1063083D01*
X182487Y-1062667D01*
X182867Y-1061917D01*
G01X186573Y-1065000D02*
X186700Y-1063917D01*
X186890Y-1063000D01*
X187143Y-1062167D01*
X187460Y-1061250D01*
X187967Y-1060000D01*
X185433D01*
G01X190977Y-1063333D02*
X192623D01*
G01X195507Y-1064000D02*
X195887Y-1064583D01*
X196393Y-1064917D01*
X196963Y-1065000D01*
X197470Y-1064917D01*
X197977Y-1064500D01*
X198293Y-1064000D01*
X198357Y-1063500D01*
X198230Y-1062917D01*
X197787Y-1062500D01*
X197343Y-1062333D01*
X196773D01*
G01X197343D02*
X197723Y-1062083D01*
X198040Y-1061667D01*
X198167Y-1061167D01*
X198040Y-1060667D01*
X197723Y-1060250D01*
X197153Y-1060000D01*
X196583Y-1060083D01*
X196013Y-1060417D01*
G01X200797Y-1062917D02*
X201240Y-1062333D01*
X201620Y-1062000D01*
X202127Y-1061833D01*
X202570Y-1062000D01*
X202887Y-1062333D01*
X203140Y-1062833D01*
X203203Y-1063417D01*
X203140Y-1063917D01*
X202887Y-1064417D01*
X202507Y-1064833D01*
X202063Y-1065000D01*
X201557Y-1064833D01*
X201113Y-1064333D01*
X200860Y-1063583D01*
X200797Y-1062750D01*
X200923Y-1061667D01*
X201113Y-1061083D01*
X201430Y-1060500D01*
X201873Y-1060083D01*
X202317Y-1060000D01*
X202760Y-1060167D01*
X203077Y-1060583D01*
G01X207100Y-1065000D02*
Y-1060000D01*
X206340Y-1061000D01*
G01Y-1065000D02*
X207860D01*
G01X212960D02*
Y-1060000D01*
X210617Y-1063583D01*
X213783D01*
G01X232000Y-995000D02*
Y-1070000D01*
G01Y-1045000D02*
X335000D01*
Y-1020000D01*
G01X232000D02*
X335000D01*
G01X337000Y-995000D02*
Y-1070000D01*
G01X335000Y-995000D02*
Y-1070000D01*
G01X342507Y-1055000D02*
Y-1050000D01*
X343773D01*
X344280Y-1050250D01*
X344660Y-1050583D01*
X344977Y-1051083D01*
X345230Y-1051667D01*
X345293Y-1052500D01*
X345230Y-1053333D01*
X344977Y-1053917D01*
X344660Y-1054417D01*
X344280Y-1054750D01*
X343773Y-1055000D01*
X342507D01*
G01X347417D02*
X349000Y-1050000D01*
X350583Y-1055000D01*
G01X350013Y-1053250D02*
X347987D01*
G01X354100Y-1050000D02*
Y-1055000D01*
G01X352643Y-1050000D02*
X355557D01*
G01X360467Y-1055000D02*
X357933D01*
Y-1050000D01*
X360467D01*
G01X359453Y-1052417D02*
X357933D01*
G01X364300Y-1055167D02*
X364173Y-1055083D01*
Y-1054917D01*
X364300Y-1054833D01*
X364427Y-1054917D01*
Y-1055083D01*
X364300Y-1055167D01*
G01Y-1052917D02*
X364173Y-1052833D01*
Y-1052667D01*
X364300Y-1052583D01*
X364427Y-1052667D01*
Y-1052833D01*
X364300Y-1052917D01*
G01X337000Y-1045000D02*
X537000D01*
G01X342633Y-1030000D02*
Y-1025000D01*
X344153D01*
X344660Y-1025250D01*
X345040Y-1025833D01*
X345167Y-1026500D01*
X345040Y-1027167D01*
X344723Y-1027667D01*
X344153Y-1027917D01*
X342633D01*
G01X347860Y-1030167D02*
X350140Y-1025000D01*
G01X352643Y-1030000D02*
Y-1025000D01*
X355557Y-1030000D01*
Y-1025000D01*
G01X359200Y-1030167D02*
X359073Y-1030083D01*
Y-1029917D01*
X359200Y-1029833D01*
X359327Y-1029917D01*
Y-1030083D01*
X359200Y-1030167D01*
G01Y-1027917D02*
X359073Y-1027833D01*
Y-1027667D01*
X359200Y-1027583D01*
X359327Y-1027667D01*
Y-1027833D01*
X359200Y-1027917D01*
G01X342633Y-1005000D02*
Y-1000000D01*
X344153D01*
X344660Y-1000250D01*
X345040Y-1000833D01*
X345167Y-1001500D01*
X345040Y-1002167D01*
X344723Y-1002667D01*
X344153Y-1002917D01*
X342633D01*
G01X347733Y-1005000D02*
Y-1000000D01*
X349317D01*
X349823Y-1000250D01*
X350140Y-1000583D01*
X350267Y-1001250D01*
X350140Y-1001917D01*
X349760Y-1002333D01*
X349317Y-1002583D01*
X347733D01*
G01X349317D02*
X350267Y-1005000D01*
G01X354100D02*
X353593Y-1004917D01*
X353150Y-1004583D01*
X352770Y-1004083D01*
X352517Y-1003500D01*
X352390Y-1002833D01*
Y-1002167D01*
X352517Y-1001500D01*
X352770Y-1000917D01*
X353150Y-1000417D01*
X353593Y-1000083D01*
X354100Y-1000000D01*
X354607Y-1000083D01*
X355050Y-1000417D01*
X355430Y-1000917D01*
X355683Y-1001500D01*
X355810Y-1002167D01*
Y-1002833D01*
X355683Y-1003500D01*
X355430Y-1004083D01*
X355050Y-1004583D01*
X354607Y-1004917D01*
X354100Y-1005000D01*
G01X357933Y-1004000D02*
X358250Y-1004500D01*
X358630Y-1004833D01*
X359073Y-1005000D01*
X359580Y-1004833D01*
X359960Y-1004500D01*
X360340Y-1004000D01*
X360467Y-1003333D01*
Y-1000000D01*
G01X365567Y-1005000D02*
X363033D01*
Y-1000000D01*
X365567D01*
G01X364553Y-1002417D02*
X363033D01*
G01X370793Y-1000417D02*
X370413Y-1000167D01*
X369970Y-1000000D01*
X369463D01*
X368893Y-1000250D01*
X368450Y-1000667D01*
X368133Y-1001167D01*
X367880Y-1002000D01*
X367817Y-1002750D01*
X367943Y-1003500D01*
X368133Y-1004000D01*
X368513Y-1004500D01*
X368957Y-1004833D01*
X369400Y-1005000D01*
X369843D01*
X370287Y-1004833D01*
X370667Y-1004583D01*
X370983Y-1004250D01*
G01X374500Y-1000000D02*
Y-1005000D01*
G01X373043Y-1000000D02*
X375957D01*
G01X379600Y-1005167D02*
X379473Y-1005083D01*
Y-1004917D01*
X379600Y-1004833D01*
X379727Y-1004917D01*
Y-1005083D01*
X379600Y-1005167D01*
G01Y-1002917D02*
X379473Y-1002833D01*
Y-1002667D01*
X379600Y-1002583D01*
X379727Y-1002667D01*
Y-1002833D01*
X379600Y-1002917D01*
G01X337000Y-1020000D02*
X537000D01*
G01X452000Y-1045000D02*
Y-1070000D01*
G01X454633Y-1047500D02*
Y-1052500D01*
X457167D01*
G01X460240Y-1047500D02*
X461760D01*
G01X461000D02*
Y-1052500D01*
G01X460240D02*
X461760D01*
G01X466607Y-1049833D02*
X466860Y-1049583D01*
X467050Y-1049167D01*
X467177Y-1048583D01*
X467050Y-1048083D01*
X466797Y-1047750D01*
X466353Y-1047500D01*
X464643D01*
Y-1052500D01*
X466733D01*
X467177Y-1052167D01*
X467430Y-1051667D01*
X467557Y-1051083D01*
X467430Y-1050500D01*
X467050Y-1050000D01*
X466607Y-1049833D01*
X464643D01*
G01X471200Y-1052667D02*
X471073Y-1052583D01*
Y-1052417D01*
X471200Y-1052333D01*
X471327Y-1052417D01*
Y-1052583D01*
X471200Y-1052667D01*
G01Y-1050417D02*
X471073Y-1050333D01*
Y-1050167D01*
X471200Y-1050083D01*
X471327Y-1050167D01*
Y-1050333D01*
X471200Y-1050417D01*
G01X495000Y-1045000D02*
Y-1070000D01*
G01X498900Y-1047500D02*
Y-1052500D01*
G01X497443Y-1047500D02*
X500357D01*
G01X504000Y-1052500D02*
X503620Y-1052417D01*
X503240Y-1052083D01*
X502987Y-1051500D01*
X502860Y-1050833D01*
X502987Y-1050167D01*
X503240Y-1049583D01*
X503620Y-1049250D01*
X504000Y-1049167D01*
X504380Y-1049250D01*
X504760Y-1049583D01*
X505013Y-1050167D01*
X505077Y-1050833D01*
X505013Y-1051500D01*
X504760Y-1052083D01*
X504380Y-1052417D01*
X504000Y-1052500D01*
G01X509100D02*
X508720Y-1052417D01*
X508340Y-1052083D01*
X508087Y-1051500D01*
X507960Y-1050833D01*
X508087Y-1050167D01*
X508340Y-1049583D01*
X508720Y-1049250D01*
X509100Y-1049167D01*
X509480Y-1049250D01*
X509860Y-1049583D01*
X510113Y-1050167D01*
X510177Y-1050833D01*
X510113Y-1051500D01*
X509860Y-1052083D01*
X509480Y-1052417D01*
X509100Y-1052500D01*
G01X514200D02*
Y-1047500D01*
G01X519300Y-1052667D02*
X519173Y-1052583D01*
Y-1052417D01*
X519300Y-1052333D01*
X519427Y-1052417D01*
Y-1052583D01*
X519300Y-1052667D01*
G01Y-1050417D02*
X519173Y-1050333D01*
Y-1050167D01*
X519300Y-1050083D01*
X519427Y-1050167D01*
Y-1050333D01*
X519300Y-1050417D01*
G01X495000Y-1020000D02*
Y-1045000D01*
G01X497633Y-1027500D02*
Y-1022500D01*
X499217D01*
X499723Y-1022750D01*
X500040Y-1023083D01*
X500167Y-1023750D01*
X500040Y-1024417D01*
X499660Y-1024833D01*
X499217Y-1025083D01*
X497633D01*
G01X499217D02*
X500167Y-1027500D01*
G01X505267D02*
X502733D01*
Y-1022500D01*
X505267D01*
G01X504253Y-1024917D02*
X502733D01*
G01X507517Y-1022500D02*
X509100Y-1027500D01*
X510683Y-1022500D01*
G01X514200Y-1027667D02*
X514073Y-1027583D01*
Y-1027417D01*
X514200Y-1027333D01*
X514327Y-1027417D01*
Y-1027583D01*
X514200Y-1027667D01*
G01Y-1025417D02*
X514073Y-1025333D01*
Y-1025167D01*
X514200Y-1025083D01*
X514327Y-1025167D01*
Y-1025333D01*
X514200Y-1025417D01*
G01X503013Y-1073167D02*
X503120Y-1073042D01*
X503200Y-1072833D01*
X503253Y-1072542D01*
X503200Y-1072292D01*
X503093Y-1072125D01*
X502907Y-1072000D01*
X502187D01*
Y-1074500D01*
X503067D01*
X503253Y-1074333D01*
X503360Y-1074083D01*
X503413Y-1073792D01*
X503360Y-1073500D01*
X503200Y-1073250D01*
X503013Y-1073167D01*
X502187D01*
G01X505480Y-1074500D02*
Y-1072833D01*
G01Y-1073125D02*
X505373Y-1072958D01*
X505213Y-1072875D01*
X505027Y-1072833D01*
X504840Y-1072917D01*
X504680Y-1073083D01*
X504573Y-1073333D01*
X504520Y-1073667D01*
X504573Y-1074000D01*
X504680Y-1074250D01*
X504840Y-1074417D01*
X505027Y-1074500D01*
X505213Y-1074458D01*
X505373Y-1074333D01*
X505480Y-1074167D01*
G01X506800Y-1074208D02*
X506933Y-1074375D01*
X507120Y-1074500D01*
X507280D01*
X507440Y-1074417D01*
X507547Y-1074292D01*
X507600Y-1074125D01*
X507573Y-1073875D01*
X507467Y-1073750D01*
X506987Y-1073500D01*
X506880Y-1073208D01*
X506933Y-1073000D01*
X507040Y-1072875D01*
X507200Y-1072833D01*
X507360Y-1072875D01*
X507520Y-1073000D01*
G01X509000Y-1073375D02*
X509853D01*
X509773Y-1073083D01*
X509640Y-1072917D01*
X509453Y-1072833D01*
X509267Y-1072875D01*
X509107Y-1073000D01*
X509000Y-1073292D01*
X508947Y-1073542D01*
Y-1073792D01*
X509000Y-1074042D01*
X509133Y-1074292D01*
X509293Y-1074458D01*
X509480Y-1074500D01*
X509667Y-1074417D01*
X509853Y-1074167D01*
G01X511120Y-1074500D02*
Y-1072000D01*
G01Y-1073250D02*
X511253Y-1073000D01*
X511413Y-1072875D01*
X511573Y-1072833D01*
X511813Y-1072917D01*
X511973Y-1073083D01*
X512080Y-1073375D01*
Y-1073708D01*
X512027Y-1074042D01*
X511920Y-1074292D01*
X511733Y-1074458D01*
X511573Y-1074500D01*
X511413Y-1074458D01*
X511253Y-1074333D01*
X511120Y-1074125D01*
G01X513800Y-1074500D02*
X513640Y-1074458D01*
X513480Y-1074292D01*
X513373Y-1074000D01*
X513320Y-1073667D01*
X513373Y-1073333D01*
X513480Y-1073042D01*
X513640Y-1072875D01*
X513800Y-1072833D01*
X513960Y-1072875D01*
X514120Y-1073042D01*
X514227Y-1073333D01*
X514253Y-1073667D01*
X514227Y-1074000D01*
X514120Y-1074292D01*
X513960Y-1074458D01*
X513800Y-1074500D01*
G01X516480D02*
Y-1072833D01*
G01Y-1073125D02*
X516373Y-1072958D01*
X516213Y-1072875D01*
X516027Y-1072833D01*
X515840Y-1072917D01*
X515680Y-1073083D01*
X515573Y-1073333D01*
X515520Y-1073667D01*
X515573Y-1074000D01*
X515680Y-1074250D01*
X515840Y-1074417D01*
X516027Y-1074500D01*
X516213Y-1074458D01*
X516373Y-1074333D01*
X516480Y-1074167D01*
G01X517827Y-1074500D02*
Y-1072833D01*
G01Y-1073167D02*
X517960Y-1073000D01*
X518093Y-1072875D01*
X518280Y-1072833D01*
X518413Y-1072875D01*
X518573Y-1073000D01*
G01X520880Y-1072000D02*
Y-1074500D01*
G01Y-1074125D02*
X520773Y-1074333D01*
X520613Y-1074458D01*
X520427Y-1074500D01*
X520213Y-1074417D01*
X520053Y-1074208D01*
X519947Y-1073958D01*
X519920Y-1073667D01*
X519947Y-1073375D01*
X520053Y-1073125D01*
X520213Y-1072917D01*
X520427Y-1072833D01*
X520613Y-1072875D01*
X520747Y-1072958D01*
X520880Y-1073125D01*
G01X524267Y-1074500D02*
Y-1072000D01*
X524933D01*
X525147Y-1072125D01*
X525280Y-1072292D01*
X525333Y-1072625D01*
X525280Y-1072958D01*
X525120Y-1073167D01*
X524933Y-1073292D01*
X524267D01*
G01X524933D02*
X525333Y-1074500D01*
G01X526600Y-1073375D02*
X527453D01*
X527373Y-1073083D01*
X527240Y-1072917D01*
X527053Y-1072833D01*
X526867Y-1072875D01*
X526707Y-1073000D01*
X526600Y-1073292D01*
X526547Y-1073542D01*
Y-1073792D01*
X526600Y-1074042D01*
X526733Y-1074292D01*
X526893Y-1074458D01*
X527080Y-1074500D01*
X527267Y-1074417D01*
X527453Y-1074167D01*
G01X528720Y-1072833D02*
X529200Y-1074500D01*
X529680Y-1072833D01*
G01X531400Y-1074583D02*
X531347Y-1074542D01*
Y-1074458D01*
X531400Y-1074417D01*
X531453Y-1074458D01*
Y-1074542D01*
X531400Y-1074583D01*
G01X533600Y-1074500D02*
X533787Y-1074458D01*
X534000Y-1074333D01*
X534133Y-1074125D01*
X534187Y-1073833D01*
X534133Y-1073542D01*
X533973Y-1073292D01*
X533733Y-1073167D01*
X533467D01*
X533307Y-1073083D01*
X533173Y-1072875D01*
X533120Y-1072583D01*
X533200Y-1072292D01*
X533387Y-1072083D01*
X533600Y-1072000D01*
X533813Y-1072083D01*
X534000Y-1072292D01*
X534080Y-1072583D01*
X534027Y-1072875D01*
X533893Y-1073083D01*
X533733Y-1073167D01*
X533467D01*
X533227Y-1073292D01*
X533067Y-1073542D01*
X533013Y-1073833D01*
X533067Y-1074125D01*
X533200Y-1074333D01*
X533413Y-1074458D01*
X533600Y-1074500D01*
G01X536013Y-1073167D02*
X536120Y-1073042D01*
X536200Y-1072833D01*
X536253Y-1072542D01*
X536200Y-1072292D01*
X536093Y-1072125D01*
X535907Y-1072000D01*
X535187D01*
Y-1074500D01*
X536067D01*
X536253Y-1074333D01*
X536360Y-1074083D01*
X536413Y-1073792D01*
X536360Y-1073500D01*
X536200Y-1073250D01*
X536013Y-1073167D01*
X535187D01*
G01X-457143Y-1211429D02*
Y2242857D01*
X4308572D01*
Y-1211429D01*
X-457143D01*
G01X71650Y-1024800D02*
X69130Y-1024383D01*
X66925Y-1022717D01*
X65035Y-1020217D01*
X63775Y-1017300D01*
X63145Y-1013967D01*
Y-1010633D01*
X63775Y-1007300D01*
X65035Y-1004383D01*
X66925Y-1001884D01*
X69130Y-1000217D01*
X71650Y-999800D01*
X74170Y-1000217D01*
X76375Y-1001884D01*
X78265Y-1004383D01*
X79525Y-1007300D01*
X80155Y-1010633D01*
Y-1013967D01*
X79525Y-1017300D01*
X78265Y-1020217D01*
X76375Y-1022717D01*
X74170Y-1024383D01*
X71650Y-1024800D01*
G01X74170Y-1018133D02*
X77950Y-1024800D01*
G01X91495Y-1008134D02*
Y-1019800D01*
X92755Y-1022717D01*
X94645Y-1024383D01*
X96850Y-1024800D01*
X99055Y-1024383D01*
X100945Y-1022717D01*
X102205Y-1019800D01*
G01Y-1024800D02*
Y-1008134D01*
G01X127720Y-1024800D02*
Y-1008134D01*
G01Y-1011050D02*
X126460Y-1009384D01*
X124570Y-1008550D01*
X122365Y-1008134D01*
X120160Y-1008967D01*
X118270Y-1010633D01*
X117010Y-1013134D01*
X116380Y-1016467D01*
X117010Y-1019800D01*
X118270Y-1022301D01*
X120160Y-1023967D01*
X122365Y-1024800D01*
X124570Y-1024383D01*
X126460Y-1023134D01*
X127720Y-1021467D01*
G01X141895Y-1024800D02*
Y-1008134D01*
G01Y-1012300D02*
X143155Y-1010217D01*
X145045Y-1008550D01*
X147565Y-1008134D01*
X149770Y-1008550D01*
X151660Y-1010217D01*
X152605Y-1013134D01*
Y-1024800D01*
G01X172450Y-999800D02*
Y-1024800D01*
G01X168040Y-1008134D02*
X176860D01*
G01X203320Y-1024800D02*
Y-1008134D01*
G01Y-1011050D02*
X202060Y-1009384D01*
X200170Y-1008550D01*
X197965Y-1008134D01*
X195760Y-1008967D01*
X193870Y-1010633D01*
X192610Y-1013134D01*
X191980Y-1016467D01*
X192610Y-1019800D01*
X193870Y-1022301D01*
X195760Y-1023967D01*
X197965Y-1024800D01*
X200170Y-1024383D01*
X202060Y-1023134D01*
X203320Y-1021467D01*
G01X49820Y-1042350D02*
X51387D01*
Y-1044240D01*
X50917Y-1044870D01*
X50368Y-1045290D01*
X49585Y-1045500D01*
X48802Y-1045290D01*
X48253Y-1044870D01*
X47783Y-1044240D01*
X47470Y-1043505D01*
X47313Y-1042665D01*
Y-1041930D01*
X47470Y-1041300D01*
X47783Y-1040565D01*
X48253Y-1039935D01*
X48723Y-1039515D01*
X49350Y-1039200D01*
X49898D01*
X50525Y-1039410D01*
X50995Y-1039830D01*
G01X53927Y-1039200D02*
Y-1043715D01*
X54240Y-1044660D01*
X54867Y-1045290D01*
X55650Y-1045500D01*
X56433Y-1045290D01*
X57060Y-1044660D01*
X57373Y-1043715D01*
Y-1039200D01*
G01X61010D02*
X62890D01*
G01X61950D02*
Y-1045500D01*
G01X61010D02*
X62890D01*
G01X66605Y-1044660D02*
X67232Y-1045185D01*
X67937Y-1045500D01*
X68563D01*
X69190Y-1045185D01*
X69660Y-1044660D01*
X69895Y-1043925D01*
X69738Y-1043190D01*
X69347Y-1042560D01*
X68642Y-1042140D01*
X67702Y-1041930D01*
X67153Y-1041510D01*
X66918Y-1040775D01*
X67075Y-1040040D01*
X67467Y-1039515D01*
X68015Y-1039200D01*
X68563D01*
X69112Y-1039410D01*
X69582Y-1039935D01*
G01X72905Y-1045500D02*
Y-1039200D01*
G01X76195D02*
Y-1045500D01*
G01Y-1042350D02*
X72905D01*
G01X78892Y-1045500D02*
X80850Y-1039200D01*
X82808Y-1045500D01*
G01X82103Y-1043295D02*
X79597D01*
G01X85348Y-1045500D02*
Y-1039200D01*
X88952Y-1045500D01*
Y-1039200D01*
G01X98027Y-1045500D02*
Y-1039200D01*
X99593D01*
X100220Y-1039515D01*
X100690Y-1039935D01*
X101082Y-1040565D01*
X101395Y-1041300D01*
X101473Y-1042350D01*
X101395Y-1043400D01*
X101082Y-1044135D01*
X100690Y-1044765D01*
X100220Y-1045185D01*
X99593Y-1045500D01*
X98027D01*
G01X105110Y-1039200D02*
X106990D01*
G01X106050D02*
Y-1045500D01*
G01X105110D02*
X106990D01*
G01X110705Y-1044660D02*
X111332Y-1045185D01*
X112037Y-1045500D01*
X112663D01*
X113290Y-1045185D01*
X113760Y-1044660D01*
X113995Y-1043925D01*
X113838Y-1043190D01*
X113447Y-1042560D01*
X112742Y-1042140D01*
X111802Y-1041930D01*
X111253Y-1041510D01*
X111018Y-1040775D01*
X111175Y-1040040D01*
X111567Y-1039515D01*
X112115Y-1039200D01*
X112663D01*
X113212Y-1039410D01*
X113682Y-1039935D01*
G01X118650Y-1039200D02*
Y-1045500D01*
G01X116848Y-1039200D02*
X120452D01*
G01X124950Y-1045710D02*
X124793Y-1045605D01*
Y-1045395D01*
X124950Y-1045290D01*
X125107Y-1045395D01*
Y-1045605D01*
X124950Y-1045710D01*
G01X131093Y-1046655D02*
X131407Y-1045290D01*
G01X137550Y-1039200D02*
Y-1045500D01*
G01X135748Y-1039200D02*
X139352D01*
G01X141892Y-1045500D02*
X143850Y-1039200D01*
X145808Y-1045500D01*
G01X145103Y-1043295D02*
X142597D01*
G01X150150Y-1045500D02*
X149523Y-1045395D01*
X148975Y-1044975D01*
X148505Y-1044345D01*
X148192Y-1043610D01*
X148035Y-1042770D01*
Y-1041930D01*
X148192Y-1041090D01*
X148505Y-1040355D01*
X148975Y-1039725D01*
X149523Y-1039305D01*
X150150Y-1039200D01*
X150777Y-1039305D01*
X151325Y-1039725D01*
X151795Y-1040355D01*
X152108Y-1041090D01*
X152265Y-1041930D01*
Y-1042770D01*
X152108Y-1043610D01*
X151795Y-1044345D01*
X151325Y-1044975D01*
X150777Y-1045395D01*
X150150Y-1045500D01*
G01X156450D02*
Y-1042665D01*
X154883Y-1039200D01*
G01X158017D02*
X156450Y-1042665D01*
G01X161027Y-1039200D02*
Y-1043715D01*
X161340Y-1044660D01*
X161967Y-1045290D01*
X162750Y-1045500D01*
X163533Y-1045290D01*
X164160Y-1044660D01*
X164473Y-1043715D01*
Y-1039200D01*
G01X167092Y-1045500D02*
X169050Y-1039200D01*
X171008Y-1045500D01*
G01X170303Y-1043295D02*
X167797D01*
G01X173548Y-1045500D02*
Y-1039200D01*
X177152Y-1045500D01*
Y-1039200D01*
G01X51073Y-1049725D02*
X50603Y-1049410D01*
X50055Y-1049200D01*
X49428D01*
X48723Y-1049515D01*
X48175Y-1050040D01*
X47783Y-1050670D01*
X47470Y-1051720D01*
X47392Y-1052665D01*
X47548Y-1053610D01*
X47783Y-1054240D01*
X48253Y-1054870D01*
X48802Y-1055290D01*
X49350Y-1055500D01*
X49898D01*
X50447Y-1055290D01*
X50917Y-1054975D01*
X51308Y-1054555D01*
G01X54710Y-1049200D02*
X56590D01*
G01X55650D02*
Y-1055500D01*
G01X54710D02*
X56590D01*
G01X61950Y-1049200D02*
Y-1055500D01*
G01X60148Y-1049200D02*
X63752D01*
G01X68250Y-1055500D02*
Y-1052665D01*
X66683Y-1049200D01*
G01X69817D02*
X68250Y-1052665D01*
G01X79127Y-1054240D02*
X79597Y-1054975D01*
X80223Y-1055395D01*
X80928Y-1055500D01*
X81555Y-1055395D01*
X82182Y-1054870D01*
X82573Y-1054240D01*
X82652Y-1053610D01*
X82495Y-1052875D01*
X81947Y-1052350D01*
X81398Y-1052140D01*
X80693D01*
G01X81398D02*
X81868Y-1051825D01*
X82260Y-1051300D01*
X82417Y-1050670D01*
X82260Y-1050040D01*
X81868Y-1049515D01*
X81163Y-1049200D01*
X80458Y-1049305D01*
X79753Y-1049725D01*
G01X85427Y-1054240D02*
X85897Y-1054975D01*
X86523Y-1055395D01*
X87228Y-1055500D01*
X87855Y-1055395D01*
X88482Y-1054870D01*
X88873Y-1054240D01*
X88952Y-1053610D01*
X88795Y-1052875D01*
X88247Y-1052350D01*
X87698Y-1052140D01*
X86993D01*
G01X87698D02*
X88168Y-1051825D01*
X88560Y-1051300D01*
X88717Y-1050670D01*
X88560Y-1050040D01*
X88168Y-1049515D01*
X87463Y-1049200D01*
X86758Y-1049305D01*
X86053Y-1049725D01*
G01X91727Y-1054240D02*
X92197Y-1054975D01*
X92823Y-1055395D01*
X93528Y-1055500D01*
X94155Y-1055395D01*
X94782Y-1054870D01*
X95173Y-1054240D01*
X95252Y-1053610D01*
X95095Y-1052875D01*
X94547Y-1052350D01*
X93998Y-1052140D01*
X93293D01*
G01X93998D02*
X94468Y-1051825D01*
X94860Y-1051300D01*
X95017Y-1050670D01*
X94860Y-1050040D01*
X94468Y-1049515D01*
X93763Y-1049200D01*
X93058Y-1049305D01*
X92353Y-1049725D01*
G01X99593Y-1055500D02*
X99750Y-1054135D01*
X99985Y-1052980D01*
X100298Y-1051930D01*
X100690Y-1050775D01*
X101317Y-1049200D01*
X98183D01*
G01X105893Y-1055500D02*
X106050Y-1054135D01*
X106285Y-1052980D01*
X106598Y-1051930D01*
X106990Y-1050775D01*
X107617Y-1049200D01*
X104483D01*
G01X112193Y-1056655D02*
X112507Y-1055290D01*
G01X118650Y-1049200D02*
Y-1055500D01*
G01X116848Y-1049200D02*
X120452D01*
G01X122992Y-1055500D02*
X124950Y-1049200D01*
X126908Y-1055500D01*
G01X126203Y-1053295D02*
X123697D01*
G01X130310Y-1049200D02*
X132190D01*
G01X131250D02*
Y-1055500D01*
G01X130310D02*
X132190D01*
G01X135200Y-1049200D02*
X136297Y-1055500D01*
X137550Y-1049200D01*
X138803Y-1055500D01*
X139900Y-1049200D01*
G01X141892Y-1055500D02*
X143850Y-1049200D01*
X145808Y-1055500D01*
G01X145103Y-1053295D02*
X142597D01*
G01X148348Y-1055500D02*
Y-1049200D01*
X151952Y-1055500D01*
Y-1049200D01*
G01X162358Y-1057600D02*
X161575Y-1056550D01*
X161183Y-1055500D01*
Y-1051300D01*
X161575Y-1050250D01*
X162358Y-1049200D01*
G01X173783Y-1055500D02*
Y-1049200D01*
X175742D01*
X176368Y-1049515D01*
X176760Y-1049935D01*
X176917Y-1050775D01*
X176760Y-1051615D01*
X176290Y-1052140D01*
X175742Y-1052455D01*
X173783D01*
G01X175742D02*
X176917Y-1055500D01*
G01X181650Y-1055710D02*
X181493Y-1055605D01*
Y-1055395D01*
X181650Y-1055290D01*
X181807Y-1055395D01*
Y-1055605D01*
X181650Y-1055710D01*
G01X187950Y-1055500D02*
X187323Y-1055395D01*
X186775Y-1054975D01*
X186305Y-1054345D01*
X185992Y-1053610D01*
X185835Y-1052770D01*
Y-1051930D01*
X185992Y-1051090D01*
X186305Y-1050355D01*
X186775Y-1049725D01*
X187323Y-1049305D01*
X187950Y-1049200D01*
X188577Y-1049305D01*
X189125Y-1049725D01*
X189595Y-1050355D01*
X189908Y-1051090D01*
X190065Y-1051930D01*
Y-1052770D01*
X189908Y-1053610D01*
X189595Y-1054345D01*
X189125Y-1054975D01*
X188577Y-1055395D01*
X187950Y-1055500D01*
G01X194250Y-1055710D02*
X194093Y-1055605D01*
Y-1055395D01*
X194250Y-1055290D01*
X194407Y-1055395D01*
Y-1055605D01*
X194250Y-1055710D01*
G01X202273Y-1049725D02*
X201803Y-1049410D01*
X201255Y-1049200D01*
X200628D01*
X199923Y-1049515D01*
X199375Y-1050040D01*
X198983Y-1050670D01*
X198670Y-1051720D01*
X198592Y-1052665D01*
X198748Y-1053610D01*
X198983Y-1054240D01*
X199453Y-1054870D01*
X200002Y-1055290D01*
X200550Y-1055500D01*
X201098D01*
X201647Y-1055290D01*
X202117Y-1054975D01*
X202508Y-1054555D01*
G01X206850Y-1055710D02*
X206693Y-1055605D01*
Y-1055395D01*
X206850Y-1055290D01*
X207007Y-1055395D01*
Y-1055605D01*
X206850Y-1055710D01*
G01X213542Y-1057600D02*
X214325Y-1056550D01*
X214717Y-1055500D01*
Y-1051300D01*
X214325Y-1050250D01*
X213542Y-1049200D01*
G01X47548Y-1035500D02*
Y-1029200D01*
X51152Y-1035500D01*
Y-1029200D01*
G01X55650Y-1035500D02*
X55023Y-1035395D01*
X54475Y-1034975D01*
X54005Y-1034345D01*
X53692Y-1033610D01*
X53535Y-1032770D01*
Y-1031930D01*
X53692Y-1031090D01*
X54005Y-1030355D01*
X54475Y-1029725D01*
X55023Y-1029305D01*
X55650Y-1029200D01*
X56277Y-1029305D01*
X56825Y-1029725D01*
X57295Y-1030355D01*
X57608Y-1031090D01*
X57765Y-1031930D01*
Y-1032770D01*
X57608Y-1033610D01*
X57295Y-1034345D01*
X56825Y-1034975D01*
X56277Y-1035395D01*
X55650Y-1035500D01*
G01X61950Y-1035710D02*
X61793Y-1035605D01*
Y-1035395D01*
X61950Y-1035290D01*
X62107Y-1035395D01*
Y-1035605D01*
X61950Y-1035710D01*
G01X66762Y-1030250D02*
X67232Y-1029620D01*
X67780Y-1029305D01*
X68407Y-1029200D01*
X69190Y-1029410D01*
X69738Y-1029935D01*
X69895Y-1030565D01*
X69817Y-1031195D01*
X69503Y-1031720D01*
X67937Y-1032770D01*
X67232Y-1033505D01*
X66762Y-1034555D01*
X66605Y-1035500D01*
X69895D01*
G01X74550D02*
Y-1029200D01*
X73610Y-1030460D01*
G01Y-1035500D02*
X75490D01*
G01X80850D02*
Y-1029200D01*
X79910Y-1030460D01*
G01Y-1035500D02*
X81790D01*
G01X86993Y-1036655D02*
X87307Y-1035290D01*
G01X91100Y-1029200D02*
X92197Y-1035500D01*
X93450Y-1029200D01*
X94703Y-1035500D01*
X95800Y-1029200D01*
G01X101317Y-1035500D02*
X98183D01*
Y-1029200D01*
X101317D01*
G01X100063Y-1032245D02*
X98183D01*
G01X104248Y-1035500D02*
Y-1029200D01*
X107852Y-1035500D01*
Y-1029200D01*
G01X110705Y-1035500D02*
Y-1029200D01*
G01X113995D02*
Y-1035500D01*
G01Y-1032350D02*
X110705D01*
G01X116927Y-1029200D02*
Y-1033715D01*
X117240Y-1034660D01*
X117867Y-1035290D01*
X118650Y-1035500D01*
X119433Y-1035290D01*
X120060Y-1034660D01*
X120373Y-1033715D01*
Y-1029200D01*
G01X122992Y-1035500D02*
X124950Y-1029200D01*
X126908Y-1035500D01*
G01X126203Y-1033295D02*
X123697D01*
G01X136062Y-1030250D02*
X136532Y-1029620D01*
X137080Y-1029305D01*
X137707Y-1029200D01*
X138490Y-1029410D01*
X139038Y-1029935D01*
X139195Y-1030565D01*
X139117Y-1031195D01*
X138803Y-1031720D01*
X137237Y-1032770D01*
X136532Y-1033505D01*
X136062Y-1034555D01*
X135905Y-1035500D01*
X139195D01*
G01X142048D02*
Y-1029200D01*
X145652Y-1035500D01*
Y-1029200D01*
G01X148427Y-1035500D02*
Y-1029200D01*
X149993D01*
X150620Y-1029515D01*
X151090Y-1029935D01*
X151482Y-1030565D01*
X151795Y-1031300D01*
X151873Y-1032350D01*
X151795Y-1033400D01*
X151482Y-1034135D01*
X151090Y-1034765D01*
X150620Y-1035185D01*
X149993Y-1035500D01*
X148427D01*
G01X161183D02*
Y-1029200D01*
X163142D01*
X163768Y-1029515D01*
X164160Y-1029935D01*
X164317Y-1030775D01*
X164160Y-1031615D01*
X163690Y-1032140D01*
X163142Y-1032455D01*
X161183D01*
G01X163142D02*
X164317Y-1035500D01*
G01X167327D02*
Y-1029200D01*
X168893D01*
X169520Y-1029515D01*
X169990Y-1029935D01*
X170382Y-1030565D01*
X170695Y-1031300D01*
X170773Y-1032350D01*
X170695Y-1033400D01*
X170382Y-1034135D01*
X169990Y-1034765D01*
X169520Y-1035185D01*
X168893Y-1035500D01*
X167327D01*
G01X175350Y-1035710D02*
X175193Y-1035605D01*
Y-1035395D01*
X175350Y-1035290D01*
X175507Y-1035395D01*
Y-1035605D01*
X175350Y-1035710D01*
G01X243000Y-1004500D02*
Y-1012500D01*
X247000D01*
G01X254800D02*
Y-1007167D01*
G01Y-1008100D02*
X254400Y-1007567D01*
X253800Y-1007300D01*
X253100Y-1007167D01*
X252400Y-1007433D01*
X251800Y-1007967D01*
X251400Y-1008767D01*
X251200Y-1009833D01*
X251400Y-1010900D01*
X251800Y-1011700D01*
X252400Y-1012233D01*
X253100Y-1012500D01*
X253800Y-1012367D01*
X254400Y-1011967D01*
X254800Y-1011434D01*
G01X258900Y-1014900D02*
X259500Y-1015167D01*
X260300Y-1014900D01*
X260800Y-1014367D01*
X261200Y-1013700D01*
X261800Y-1011567D01*
X263100Y-1007167D01*
G01X259900D02*
X261800Y-1011567D01*
G01X267500Y-1008900D02*
X270700D01*
X270400Y-1007967D01*
X269900Y-1007433D01*
X269200Y-1007167D01*
X268500Y-1007300D01*
X267900Y-1007700D01*
X267500Y-1008633D01*
X267300Y-1009434D01*
Y-1010233D01*
X267500Y-1011033D01*
X268000Y-1011833D01*
X268600Y-1012367D01*
X269300Y-1012500D01*
X270000Y-1012233D01*
X270700Y-1011434D01*
G01X275600Y-1012500D02*
Y-1007167D01*
G01Y-1008233D02*
X276100Y-1007700D01*
X276600Y-1007300D01*
X277300Y-1007167D01*
X277800Y-1007300D01*
X278400Y-1007700D01*
G01X262100Y-1054500D02*
X265900D01*
X262100Y-1062500D01*
X265900D01*
G01X272000Y-1057167D02*
Y-1062500D01*
G01Y-1055033D02*
X271800Y-1054900D01*
Y-1054633D01*
X272000Y-1054500D01*
X272200Y-1054633D01*
Y-1054900D01*
X272000Y-1055033D01*
G01X278700Y-1059833D02*
X281300D01*
G01X286200Y-1065167D02*
Y-1057167D01*
G01Y-1058367D02*
X286700Y-1057700D01*
X287200Y-1057300D01*
X288000Y-1057167D01*
X288700Y-1057300D01*
X289400Y-1057967D01*
X289700Y-1058900D01*
X289800Y-1059833D01*
X289700Y-1060767D01*
X289400Y-1061700D01*
X288800Y-1062233D01*
X288000Y-1062500D01*
X287300Y-1062367D01*
X286600Y-1061967D01*
X286200Y-1061434D01*
G01X296000Y-1057167D02*
Y-1062500D01*
G01Y-1055033D02*
X295800Y-1054900D01*
Y-1054633D01*
X296000Y-1054500D01*
X296200Y-1054633D01*
Y-1054900D01*
X296000Y-1055033D01*
G01X302300Y-1062500D02*
Y-1057167D01*
G01Y-1058500D02*
X302700Y-1057833D01*
X303300Y-1057300D01*
X304100Y-1057167D01*
X304800Y-1057300D01*
X305400Y-1057833D01*
X305700Y-1058767D01*
Y-1062500D01*
G01X310600Y-1064500D02*
X311300Y-1065033D01*
X312100Y-1065167D01*
X312800Y-1065033D01*
X313400Y-1064367D01*
X313800Y-1063433D01*
Y-1057167D01*
G01Y-1058233D02*
X313400Y-1057700D01*
X312800Y-1057300D01*
X312100Y-1057167D01*
X311300Y-1057433D01*
X310800Y-1057967D01*
X310400Y-1058900D01*
X310200Y-1059833D01*
X310300Y-1060633D01*
X310700Y-1061567D01*
X311300Y-1062233D01*
X312100Y-1062500D01*
X312700Y-1062367D01*
X313400Y-1061833D01*
X313800Y-1061300D01*
G01X272100Y-1033500D02*
X274100D01*
Y-1035900D01*
X273500Y-1036700D01*
X272800Y-1037233D01*
X271800Y-1037500D01*
X270800Y-1037233D01*
X270100Y-1036700D01*
X269500Y-1035900D01*
X269100Y-1034967D01*
X268900Y-1033900D01*
Y-1032967D01*
X269100Y-1032167D01*
X269500Y-1031233D01*
X270100Y-1030433D01*
X270700Y-1029900D01*
X271500Y-1029500D01*
X272200D01*
X273000Y-1029767D01*
X273600Y-1030300D01*
G01X277200Y-1037500D02*
Y-1029500D01*
X281800Y-1037500D01*
Y-1029500D01*
G01X285300Y-1037500D02*
Y-1029500D01*
X287300D01*
X288100Y-1029900D01*
X288700Y-1030433D01*
X289200Y-1031233D01*
X289600Y-1032167D01*
X289700Y-1033500D01*
X289600Y-1034833D01*
X289200Y-1035767D01*
X288700Y-1036567D01*
X288100Y-1037100D01*
X287300Y-1037500D01*
X285300D01*
G01X294600Y-1005833D02*
X295200Y-1005033D01*
X295900Y-1004633D01*
X296700Y-1004500D01*
X297700Y-1004767D01*
X298400Y-1005433D01*
X298600Y-1006233D01*
X298500Y-1007034D01*
X298100Y-1007700D01*
X296100Y-1009033D01*
X295200Y-1009967D01*
X294600Y-1011300D01*
X294400Y-1012500D01*
X298600D01*
G01X369600Y-1055833D02*
X370200Y-1055033D01*
X370900Y-1054633D01*
X371700Y-1054500D01*
X372700Y-1054767D01*
X373400Y-1055433D01*
X373600Y-1056233D01*
X373500Y-1057034D01*
X373100Y-1057700D01*
X371100Y-1059033D01*
X370200Y-1059967D01*
X369600Y-1061300D01*
X369400Y-1062500D01*
X373600D01*
G01X379500Y-1054500D02*
X378700Y-1054767D01*
X378100Y-1055433D01*
X377700Y-1056233D01*
X377400Y-1057300D01*
X377300Y-1058500D01*
X377400Y-1059700D01*
X377700Y-1060767D01*
X378100Y-1061567D01*
X378700Y-1062233D01*
X379500Y-1062500D01*
X380300Y-1062233D01*
X380900Y-1061567D01*
X381300Y-1060767D01*
X381600Y-1059700D01*
X381700Y-1058500D01*
X381600Y-1057300D01*
X381300Y-1056233D01*
X380900Y-1055433D01*
X380300Y-1054767D01*
X379500Y-1054500D01*
G01X385600Y-1055833D02*
X386200Y-1055033D01*
X386900Y-1054633D01*
X387700Y-1054500D01*
X388700Y-1054767D01*
X389400Y-1055433D01*
X389600Y-1056233D01*
X389500Y-1057034D01*
X389100Y-1057700D01*
X387100Y-1059033D01*
X386200Y-1059967D01*
X385600Y-1061300D01*
X385400Y-1062500D01*
X389600D01*
G01X393600Y-1055833D02*
X394200Y-1055033D01*
X394900Y-1054633D01*
X395700Y-1054500D01*
X396700Y-1054767D01*
X397400Y-1055433D01*
X397600Y-1056233D01*
X397500Y-1057034D01*
X397100Y-1057700D01*
X395100Y-1059033D01*
X394200Y-1059967D01*
X393600Y-1061300D01*
X393400Y-1062500D01*
X397600D01*
G01X401700Y-1062767D02*
X405300Y-1054500D01*
G01X411500Y-1062500D02*
Y-1054500D01*
X410300Y-1056100D01*
G01Y-1062500D02*
X412700D01*
G01X417600Y-1055833D02*
X418200Y-1055033D01*
X418900Y-1054633D01*
X419700Y-1054500D01*
X420700Y-1054767D01*
X421400Y-1055433D01*
X421600Y-1056233D01*
X421500Y-1057034D01*
X421100Y-1057700D01*
X419100Y-1059033D01*
X418200Y-1059967D01*
X417600Y-1061300D01*
X417400Y-1062500D01*
X421600D01*
G01X425700Y-1062767D02*
X429300Y-1054500D01*
G01X435500Y-1062500D02*
Y-1054500D01*
X434300Y-1056100D01*
G01Y-1062500D02*
X436700D01*
G01X441300Y-1060900D02*
X441900Y-1061833D01*
X442700Y-1062367D01*
X443600Y-1062500D01*
X444400Y-1062367D01*
X445200Y-1061700D01*
X445700Y-1060900D01*
X445800Y-1060100D01*
X445600Y-1059167D01*
X444900Y-1058500D01*
X444200Y-1058233D01*
X443300D01*
G01X444200D02*
X444800Y-1057833D01*
X445300Y-1057167D01*
X445500Y-1056367D01*
X445300Y-1055567D01*
X444800Y-1054900D01*
X443900Y-1054500D01*
X443000Y-1054633D01*
X442100Y-1055167D01*
G01X369300Y-1040000D02*
Y-1032000D01*
X371300D01*
X372100Y-1032400D01*
X372700Y-1032933D01*
X373200Y-1033733D01*
X373600Y-1034667D01*
X373700Y-1036000D01*
X373600Y-1037333D01*
X373200Y-1038267D01*
X372700Y-1039067D01*
X372100Y-1039600D01*
X371300Y-1040000D01*
X369300D01*
G01X377000D02*
X379500Y-1032000D01*
X382000Y-1040000D01*
G01X381100Y-1037200D02*
X377900D01*
G01X385600Y-1040000D02*
Y-1032000D01*
X389400D01*
G01X388000Y-1035867D02*
X385600D01*
G01X395500Y-1032000D02*
X394700Y-1032267D01*
X394100Y-1032933D01*
X393700Y-1033733D01*
X393400Y-1034800D01*
X393300Y-1036000D01*
X393400Y-1037200D01*
X393700Y-1038267D01*
X394100Y-1039067D01*
X394700Y-1039733D01*
X395500Y-1040000D01*
X396300Y-1039733D01*
X396900Y-1039067D01*
X397300Y-1038267D01*
X397600Y-1037200D01*
X397700Y-1036000D01*
X397600Y-1034800D01*
X397300Y-1033733D01*
X396900Y-1032933D01*
X396300Y-1032267D01*
X395500Y-1032000D01*
G01X403500D02*
Y-1040000D01*
G01X401200Y-1032000D02*
X405800D01*
G01X409500Y-1040000D02*
Y-1032000D01*
X411900D01*
X412700Y-1032400D01*
X413300Y-1033333D01*
X413500Y-1034400D01*
X413300Y-1035467D01*
X412800Y-1036267D01*
X411900Y-1036667D01*
X409500D01*
G01X420300Y-1035733D02*
X420700Y-1035333D01*
X421000Y-1034667D01*
X421200Y-1033733D01*
X421000Y-1032933D01*
X420600Y-1032400D01*
X419900Y-1032000D01*
X417200D01*
Y-1040000D01*
X420500D01*
X421200Y-1039467D01*
X421600Y-1038667D01*
X421800Y-1037733D01*
X421600Y-1036800D01*
X421000Y-1036000D01*
X420300Y-1035733D01*
X417200D01*
G01X427500Y-1040000D02*
Y-1032000D01*
X426300Y-1033600D01*
G01Y-1040000D02*
X428700D01*
G01X433000D02*
X435500Y-1032000D01*
X438000Y-1040000D01*
G01X437100Y-1037200D02*
X433900D01*
G01X441600Y-1040000D02*
Y-1032000D01*
X445400D01*
G01X444000Y-1035867D02*
X441600D01*
G01X451500Y-1032000D02*
X450700Y-1032267D01*
X450100Y-1032933D01*
X449700Y-1033733D01*
X449400Y-1034800D01*
X449300Y-1036000D01*
X449400Y-1037200D01*
X449700Y-1038267D01*
X450100Y-1039067D01*
X450700Y-1039733D01*
X451500Y-1040000D01*
X452300Y-1039733D01*
X452900Y-1039067D01*
X453300Y-1038267D01*
X453600Y-1037200D01*
X453700Y-1036000D01*
X453600Y-1034800D01*
X453300Y-1033733D01*
X452900Y-1032933D01*
X452300Y-1032267D01*
X451500Y-1032000D01*
G01X389600Y-1012500D02*
Y-1004500D01*
X393400D01*
G01X392000Y-1008367D02*
X389600D01*
G01X399500Y-1004500D02*
X398700Y-1004767D01*
X398100Y-1005433D01*
X397700Y-1006233D01*
X397400Y-1007300D01*
X397300Y-1008500D01*
X397400Y-1009700D01*
X397700Y-1010767D01*
X398100Y-1011567D01*
X398700Y-1012233D01*
X399500Y-1012500D01*
X400300Y-1012233D01*
X400900Y-1011567D01*
X401300Y-1010767D01*
X401600Y-1009700D01*
X401700Y-1008500D01*
X401600Y-1007300D01*
X401300Y-1006233D01*
X400900Y-1005433D01*
X400300Y-1004767D01*
X399500Y-1004500D01*
G01X407500D02*
Y-1012500D01*
G01X405200Y-1004500D02*
X409800D01*
G01X412500Y-1015167D02*
X418500D01*
G01X421500Y-1012500D02*
Y-1004500D01*
X423900D01*
X424700Y-1004900D01*
X425300Y-1005833D01*
X425500Y-1006900D01*
X425300Y-1007967D01*
X424800Y-1008767D01*
X423900Y-1009167D01*
X421500D01*
G01X429300Y-1012500D02*
Y-1004500D01*
X431300D01*
X432100Y-1004900D01*
X432700Y-1005433D01*
X433200Y-1006233D01*
X433600Y-1007167D01*
X433700Y-1008500D01*
X433600Y-1009833D01*
X433200Y-1010767D01*
X432700Y-1011567D01*
X432100Y-1012100D01*
X431300Y-1012500D01*
X429300D01*
G01X440300Y-1008233D02*
X440700Y-1007833D01*
X441000Y-1007167D01*
X441200Y-1006233D01*
X441000Y-1005433D01*
X440600Y-1004900D01*
X439900Y-1004500D01*
X437200D01*
Y-1012500D01*
X440500D01*
X441200Y-1011967D01*
X441600Y-1011167D01*
X441800Y-1010233D01*
X441600Y-1009300D01*
X441000Y-1008500D01*
X440300Y-1008233D01*
X437200D01*
G01X444500Y-1015167D02*
X450500D01*
G01X456300Y-1008233D02*
X456700Y-1007833D01*
X457000Y-1007167D01*
X457200Y-1006233D01*
X457000Y-1005433D01*
X456600Y-1004900D01*
X455900Y-1004500D01*
X453200D01*
Y-1012500D01*
X456500D01*
X457200Y-1011967D01*
X457600Y-1011167D01*
X457800Y-1010233D01*
X457600Y-1009300D01*
X457000Y-1008500D01*
X456300Y-1008233D01*
X453200D01*
G01X461300Y-1012500D02*
Y-1004500D01*
X463300D01*
X464100Y-1004900D01*
X464700Y-1005433D01*
X465200Y-1006233D01*
X465600Y-1007167D01*
X465700Y-1008500D01*
X465600Y-1009833D01*
X465200Y-1010767D01*
X464700Y-1011567D01*
X464100Y-1012100D01*
X463300Y-1012500D01*
X461300D01*
G01X468500Y-1015167D02*
X474500D01*
G01X480100Y-1008500D02*
X482100D01*
Y-1010900D01*
X481500Y-1011700D01*
X480800Y-1012233D01*
X479800Y-1012500D01*
X478800Y-1012233D01*
X478100Y-1011700D01*
X477500Y-1010900D01*
X477100Y-1009967D01*
X476900Y-1008900D01*
Y-1007967D01*
X477100Y-1007167D01*
X477500Y-1006233D01*
X478100Y-1005433D01*
X478700Y-1004900D01*
X479500Y-1004500D01*
X480200D01*
X481000Y-1004767D01*
X481600Y-1005300D01*
G01X485500Y-1012500D02*
Y-1004500D01*
X487900D01*
X488700Y-1004900D01*
X489300Y-1005833D01*
X489500Y-1006900D01*
X489300Y-1007967D01*
X488800Y-1008767D01*
X487900Y-1009167D01*
X485500D01*
G01X493300Y-1004500D02*
Y-1010233D01*
X493700Y-1011434D01*
X494500Y-1012233D01*
X495500Y-1012500D01*
X496500Y-1012233D01*
X497300Y-1011434D01*
X497700Y-1010233D01*
Y-1004500D01*
G01X458000Y-1065500D02*
Y-1057500D01*
X456800Y-1059100D01*
G01Y-1065500D02*
X459200D01*
G01X464100Y-1062167D02*
X464800Y-1061233D01*
X465400Y-1060700D01*
X466200Y-1060433D01*
X466900Y-1060700D01*
X467400Y-1061233D01*
X467800Y-1062033D01*
X467900Y-1062967D01*
X467800Y-1063767D01*
X467400Y-1064567D01*
X466800Y-1065233D01*
X466100Y-1065500D01*
X465300Y-1065233D01*
X464600Y-1064434D01*
X464200Y-1063233D01*
X464100Y-1061900D01*
X464300Y-1060167D01*
X464600Y-1059233D01*
X465100Y-1058300D01*
X465800Y-1057633D01*
X466500Y-1057500D01*
X467200Y-1057767D01*
X467700Y-1058433D01*
G01X474000Y-1065767D02*
X473800Y-1065633D01*
Y-1065367D01*
X474000Y-1065233D01*
X474200Y-1065367D01*
Y-1065633D01*
X474000Y-1065767D01*
G01X480100Y-1062167D02*
X480800Y-1061233D01*
X481400Y-1060700D01*
X482200Y-1060433D01*
X482900Y-1060700D01*
X483400Y-1061233D01*
X483800Y-1062033D01*
X483900Y-1062967D01*
X483800Y-1063767D01*
X483400Y-1064567D01*
X482800Y-1065233D01*
X482100Y-1065500D01*
X481300Y-1065233D01*
X480600Y-1064434D01*
X480200Y-1063233D01*
X480100Y-1061900D01*
X480300Y-1060167D01*
X480600Y-1059233D01*
X481100Y-1058300D01*
X481800Y-1057633D01*
X482500Y-1057500D01*
X483200Y-1057767D01*
X483700Y-1058433D01*
G01X503000Y-1065500D02*
Y-1057500D01*
X501800Y-1059100D01*
G01Y-1065500D02*
X504200D01*
G01X510800D02*
X511000Y-1063767D01*
X511300Y-1062300D01*
X511700Y-1060967D01*
X512200Y-1059500D01*
X513000Y-1057500D01*
X509000D01*
G01X519000Y-1065767D02*
X518800Y-1065633D01*
Y-1065367D01*
X519000Y-1065233D01*
X519200Y-1065367D01*
Y-1065633D01*
X519000Y-1065767D01*
G01X525100Y-1058833D02*
X525700Y-1058033D01*
X526400Y-1057633D01*
X527200Y-1057500D01*
X528200Y-1057767D01*
X528900Y-1058433D01*
X529100Y-1059233D01*
X529000Y-1060034D01*
X528600Y-1060700D01*
X526600Y-1062033D01*
X525700Y-1062967D01*
X525100Y-1064300D01*
X524900Y-1065500D01*
X529100D01*
G01X523100Y-1040500D02*
Y-1032500D01*
X526900D01*
G01X525500Y-1036367D02*
X523100D01*
M02*
